FILE_TYPE = MACRO_DRAWING;
SET COLOR_WIRE YELLOW;
SET COLOR_PROP ORANGE;
SET COLOR_DOT WHITE;
SET COLOR_ARC YELLOW;
SET COLOR_BODY GREEN;
SET COLOR_NOTE PURPLE;
SET PROP_DISPLAY VALUE;
SET PAGE_NUMBER P258;
FORCEADD 74LVC2G08DP..1
(-2600 750);
FORCEPROP 1 LAST LOCATION U241
J 0
(-2425 650);
DISPLAY 0.723404 (-2425 650);
PAINT GREEN (-2425 650);
FORCEPROP 0 LAST $SEC 1
J 0
(-2425 675);
DISPLAY 0.680851 (-2425 675);
PAINT MONO (-2425 675);
DISPLAY INVISIBLE (-2425 675);
FORCEPROP 0 LAST CDS_SEC 1
J 0
(-2425 675);
DISPLAY 1.021277 (-2425 675);
DISPLAY INVISIBLE (-2425 675);
FORCEPROP 0 LASTPIN (-2900 800) $PN 1
J 2
(-2910 810);
DISPLAY 0.680851 (-2910 810);
PAINT MONO (-2910 810);
FORCEPROP 0 LASTPIN (-2900 700) $PN 2
J 2
(-2910 710);
DISPLAY 0.680851 (-2910 710);
PAINT MONO (-2910 710);
FORCEPROP 0 LASTPIN (-2300 750) $PN 7
J 0
(-2290 760);
DISPLAY 0.680851 (-2290 760);
PAINT MONO (-2290 760);
FORCEPROP 0 LASTPIN (-2600 600) $PN 4
R 1
J 2
(-2610 590);
DISPLAY 0.680851 (-2610 590);
PAINT MONO (-2610 590);
FORCEPROP 0 LASTPIN (-2600 900) $PN 8
R 1
J 0
(-2610 910);
DISPLAY 0.680851 (-2610 910);
PAINT MONO (-2610 910);
FORCEPROP 2 LAST PART_TYPE SMLF
J 0
(-2425 600);
DISPLAY 0.808511 (-2425 600);
FORCEPROP 1 LAST MATERIAL EMPTY
J 0
(-2425 425);
DISPLAY 0.723404 (-2425 425);
PAINT GREEN (-2425 425);
FORCEPROP 2 LAST VALUE 74LVC2G08DP
J 0
(-2420 536);
DISPLAY 0.808511 (-2420 536);
FORCEPROP 2 LAST CDS_LIB pure_quanta
J 0
(-2600 750);
DISPLAY INVISIBLE (-2600 750);
FORCEPROP 1 LAST NEEDS_NO_SIZE TRUE
J 0
(-2600 750);
DISPLAY 0.723404 (-2600 750);
PAINT GREEN (-2600 750);
DISPLAY INVISIBLE (-2600 750);
FORCEPROP 1 LAST CDS_LMAN_SYM_OUTLINE -150,100,150,-100
J 0
(-2600 750);
DISPLAY 0.468085 (-2600 750);
PAINT GREEN (-2600 750);
DISPLAY INVISIBLE (-2600 750);
FORCEPROP 1 LAST PATH I1
J 0
(-2600 750);
DISPLAY 0.723404 (-2600 750);
PAINT GREEN (-2600 750);
DISPLAY INVISIBLE (-2600 750);
FORCEPROP 1 LAST PART_NUMBER ALVC2G08K01
J 0
(-2425 480);
DISPLAY 0.723404 (-2425 480);
PAINT GREEN (-2425 480);
DISPLAY INVISIBLE (-2425 480);
FORCEADD OFFPAGE..1
(-3625 2800);
FORCEPROP 2 LAST $XR1 134 
J 0
(-4027 2800);
DISPLAY 0.638298 (-4027 2800);
PAINT MONO (-4027 2800);
FORCEPROP 2 LAST $XR0 131 
J 0
(-3907 2800);
DISPLAY 0.638298 (-3907 2800);
PAINT MONO (-3907 2800);
FORCEPROP 2 LAST CDS_LIB standard
J 0
(-3625 2800);
PAINT MONO (-3625 2800);
DISPLAY INVISIBLE (-3625 2800);
FORCEPROP 1 LAST OFFPAGE TRUE
J 0
(-3300 2675);
DISPLAY 0.872340 (-3300 2675);
PAINT GREEN (-3300 2675);
DISPLAY INVISIBLE (-3300 2675);
FORCEPROP 1 LAST COMMENT_BODY TRUE
J 0
(-3500 2700);
DISPLAY 0.872340 (-3500 2700);
PAINT GREEN (-3500 2700);
DISPLAY INVISIBLE (-3500 2700);
FORCEPROP 2 LAST PATH I10
J 0
(-3875 2850);
DISPLAY 1.021277 (-3875 2850);
DISPLAY INVISIBLE (-3875 2850);
FORCEADD 74LVC2G08DP..1
(-2600 2850);
FORCEPROP 1 LAST LOCATION U240
J 0
(-2450 2750);
DISPLAY 0.723404 (-2450 2750);
PAINT GREEN (-2450 2750);
FORCEPROP 0 LAST $SEC 1
J 0
(-2425 2775);
DISPLAY 0.680851 (-2425 2775);
PAINT MONO (-2425 2775);
DISPLAY INVISIBLE (-2425 2775);
FORCEPROP 0 LAST CDS_SEC 1
J 0
(-2425 2775);
DISPLAY 1.021277 (-2425 2775);
DISPLAY INVISIBLE (-2425 2775);
FORCEPROP 0 LASTPIN (-2900 2900) $PN 1
J 2
(-2910 2910);
DISPLAY 0.680851 (-2910 2910);
PAINT MONO (-2910 2910);
FORCEPROP 0 LASTPIN (-2900 2800) $PN 2
J 2
(-2910 2810);
DISPLAY 0.680851 (-2910 2810);
PAINT MONO (-2910 2810);
FORCEPROP 0 LASTPIN (-2300 2850) $PN 7
J 0
(-2290 2860);
DISPLAY 0.680851 (-2290 2860);
PAINT MONO (-2290 2860);
FORCEPROP 0 LASTPIN (-2600 2700) $PN 4
R 1
J 2
(-2610 2690);
DISPLAY 0.680851 (-2610 2690);
PAINT MONO (-2610 2690);
FORCEPROP 0 LASTPIN (-2600 3000) $PN 8
R 1
J 0
(-2610 3010);
DISPLAY 0.680851 (-2610 3010);
PAINT MONO (-2610 3010);
FORCEPROP 1 LAST MATERIAL EMPTY
J 0
(-2450 2550);
DISPLAY 0.723404 (-2450 2550);
PAINT GREEN (-2450 2550);
FORCEPROP 2 LAST PART_TYPE SMLF
J 0
(-2450 2700);
DISPLAY 0.808511 (-2450 2700);
FORCEPROP 2 LAST VALUE 74LVC2G08DP
J 0
(-2450 2650);
DISPLAY 0.808511 (-2450 2650);
FORCEPROP 1 LAST NEEDS_NO_SIZE TRUE
J 0
(-2600 2850);
DISPLAY 0.723404 (-2600 2850);
PAINT GREEN (-2600 2850);
DISPLAY INVISIBLE (-2600 2850);
FORCEPROP 1 LAST CDS_LMAN_SYM_OUTLINE -150,100,150,-100
J 0
(-2600 2850);
DISPLAY 0.468085 (-2600 2850);
PAINT GREEN (-2600 2850);
DISPLAY INVISIBLE (-2600 2850);
FORCEPROP 2 LAST CDS_LIB pure_quanta
J 0
(-2600 2850);
DISPLAY INVISIBLE (-2600 2850);
FORCEPROP 1 LAST PATH I11
J 0
(-2600 2850);
DISPLAY 0.723404 (-2600 2850);
PAINT GREEN (-2600 2850);
DISPLAY INVISIBLE (-2600 2850);
FORCEPROP 1 LAST PART_NUMBER ALVC2G08K01
J 0
(-2450 2605);
DISPLAY 0.723404 (-2450 2605);
PAINT GREEN (-2450 2605);
DISPLAY INVISIBLE (-2450 2605);
FORCEADD 74LVC2G08DP..2
(-2600 1950);
FORCEPROP 1 LAST LOCATION U240
J 0
(-2750 2250);
DISPLAY 0.723404 (-2750 2250);
PAINT GREEN (-2750 2250);
FORCEPROP 0 LAST $SEC 2
J 0
(-2750 2300);
DISPLAY 0.680851 (-2750 2300);
PAINT MONO (-2750 2300);
DISPLAY INVISIBLE (-2750 2300);
FORCEPROP 0 LAST CDS_SEC 2
J 0
(-2750 2300);
DISPLAY 1.021277 (-2750 2300);
DISPLAY INVISIBLE (-2750 2300);
FORCEPROP 0 LASTPIN (-2900 2000) $PN 5
J 2
(-2910 2010);
DISPLAY 0.680851 (-2910 2010);
PAINT MONO (-2910 2010);
FORCEPROP 0 LASTPIN (-2900 1900) $PN 6
J 2
(-2910 1910);
DISPLAY 0.680851 (-2910 1910);
PAINT MONO (-2910 1910);
FORCEPROP 0 LASTPIN (-2300 1950) $PN 3
J 0
(-2290 1960);
DISPLAY 0.680851 (-2290 1960);
PAINT MONO (-2290 1960);
FORCEPROP 2 LAST VALUE 74LVC2G08DP
J 0
(-2750 2150);
DISPLAY 0.808511 (-2750 2150);
FORCEPROP 1 LAST MATERIAL EMPTY
J 0
(-2754 2060);
DISPLAY 0.723404 (-2754 2060);
PAINT GREEN (-2754 2060);
FORCEPROP 2 LAST PART_TYPE SMLF
J 0
(-2750 2200);
DISPLAY 0.808511 (-2750 2200);
FORCEPROP 1 LAST NEEDS_NO_SIZE TRUE
J 0
(-2600 1950);
DISPLAY 0.723404 (-2600 1950);
PAINT GREEN (-2600 1950);
DISPLAY INVISIBLE (-2600 1950);
FORCEPROP 1 LAST CDS_LMAN_SYM_OUTLINE -150,100,150,-100
J 0
(-2600 1950);
DISPLAY 0.468085 (-2600 1950);
PAINT GREEN (-2600 1950);
DISPLAY INVISIBLE (-2600 1950);
FORCEPROP 2 LAST CDS_LIB pure_quanta
J 0
(-2600 1950);
DISPLAY INVISIBLE (-2600 1950);
FORCEPROP 1 LAST PATH I12
J 0
(-2600 1950);
DISPLAY 0.723404 (-2600 1950);
PAINT GREEN (-2600 1950);
DISPLAY INVISIBLE (-2600 1950);
FORCEPROP 1 LAST PART_NUMBER ALVC2G08K01
J 0
(-2754 2110);
DISPLAY 0.723404 (-2754 2110);
PAINT GREEN (-2754 2110);
DISPLAY INVISIBLE (-2754 2110);
FORCEADD 74LVC2G08DP..1
(-400 2400);
FORCEPROP 1 LAST LOCATION U242
J 0
(-675 2075);
DISPLAY 0.723404 (-675 2075);
PAINT GREEN (-675 2075);
FORCEPROP 0 LAST $SEC 1
J 0
(-750 2175);
DISPLAY 0.680851 (-750 2175);
PAINT MONO (-750 2175);
DISPLAY INVISIBLE (-750 2175);
FORCEPROP 0 LAST CDS_SEC 1
J 0
(-750 2175);
DISPLAY 1.021277 (-750 2175);
DISPLAY INVISIBLE (-750 2175);
FORCEPROP 0 LASTPIN (-700 2450) $PN 1
J 2
(-710 2460);
DISPLAY 0.680851 (-710 2460);
PAINT MONO (-710 2460);
FORCEPROP 0 LASTPIN (-700 2350) $PN 2
J 2
(-710 2360);
DISPLAY 0.680851 (-710 2360);
PAINT MONO (-710 2360);
FORCEPROP 0 LASTPIN (-100 2400) $PN 7
J 0
(-90 2410);
DISPLAY 0.680851 (-90 2410);
PAINT MONO (-90 2410);
FORCEPROP 0 LASTPIN (-400 2250) $PN 4
R 1
J 2
(-410 2240);
DISPLAY 0.680851 (-410 2240);
PAINT MONO (-410 2240);
FORCEPROP 0 LASTPIN (-400 2550) $PN 8
R 1
J 0
(-410 2560);
DISPLAY 0.680851 (-410 2560);
PAINT MONO (-410 2560);
FORCEPROP 1 LAST MATERIAL EMPTY
J 0
(-675 2125);
DISPLAY 0.723404 (-675 2125);
PAINT GREEN (-675 2125);
FORCEPROP 2 LAST VALUE 74LVC2G08DP
J 0
(-675 2025);
DISPLAY 0.808511 (-675 2025);
PAINT GREEN (-675 2025);
FORCEPROP 2 LAST CDS_LIB pure_quanta
J 0
(-400 2400);
DISPLAY INVISIBLE (-400 2400);
FORCEPROP 1 LAST CDS_LMAN_SYM_OUTLINE -150,100,150,-100
J 0
(-400 2400);
DISPLAY 0.468085 (-400 2400);
PAINT GREEN (-400 2400);
DISPLAY INVISIBLE (-400 2400);
FORCEPROP 1 LAST NEEDS_NO_SIZE TRUE
J 0
(-400 2400);
DISPLAY 0.723404 (-400 2400);
PAINT GREEN (-400 2400);
DISPLAY INVISIBLE (-400 2400);
FORCEPROP 0 LAST PART_TYPE SMLF
J 0
(-795 2038);
DISPLAY 1.021277 (-795 2038);
PAINT GREEN (-795 2038);
DISPLAY INVISIBLE (-795 2038);
FORCEPROP 1 LAST PATH I13
J 0
(-400 2400);
DISPLAY 0.723404 (-400 2400);
PAINT GREEN (-400 2400);
DISPLAY INVISIBLE (-400 2400);
FORCEPROP 1 LAST PART_NUMBER ALVC2G08K01
J 0
(-675 1975);
DISPLAY 0.723404 (-675 1975);
PAINT GREEN (-675 1975);
DISPLAY INVISIBLE (-675 1975);
FORCEADD 74LVC2G08DP..2
(-400 275);
FORCEPROP 1 LAST LOCATION U242
J 0
(-550 575);
DISPLAY 0.723404 (-550 575);
PAINT GREEN (-550 575);
FORCEPROP 0 LAST $SEC 2
J 0
(-550 625);
DISPLAY 0.680851 (-550 625);
PAINT MONO (-550 625);
DISPLAY INVISIBLE (-550 625);
FORCEPROP 0 LAST CDS_SEC 2
J 0
(-550 625);
DISPLAY 1.021277 (-550 625);
DISPLAY INVISIBLE (-550 625);
FORCEPROP 0 LASTPIN (-700 325) $PN 5
J 2
(-710 335);
DISPLAY 0.680851 (-710 335);
PAINT MONO (-710 335);
FORCEPROP 0 LASTPIN (-700 225) $PN 6
J 2
(-710 235);
DISPLAY 0.680851 (-710 235);
PAINT MONO (-710 235);
FORCEPROP 0 LASTPIN (-100 275) $PN 3
J 0
(-90 285);
DISPLAY 0.680851 (-90 285);
PAINT MONO (-90 285);
FORCEPROP 2 LAST PART_TYPE SMLF
J 0
(-550 525);
DISPLAY 0.808511 (-550 525);
FORCEPROP 2 LAST VALUE 74LVC2G08DP
J 0
(-550 475);
DISPLAY 0.808511 (-550 475);
FORCEPROP 1 LAST MATERIAL EMPTY
J 0
(-554 385);
DISPLAY 0.723404 (-554 385);
PAINT GREEN (-554 385);
FORCEPROP 2 LAST CDS_LIB pure_quanta
J 0
(-400 275);
DISPLAY INVISIBLE (-400 275);
FORCEPROP 1 LAST CDS_LMAN_SYM_OUTLINE -150,100,150,-100
J 0
(-400 275);
DISPLAY 0.468085 (-400 275);
PAINT GREEN (-400 275);
DISPLAY INVISIBLE (-400 275);
FORCEPROP 1 LAST NEEDS_NO_SIZE TRUE
J 0
(-400 275);
DISPLAY 0.723404 (-400 275);
PAINT GREEN (-400 275);
DISPLAY INVISIBLE (-400 275);
FORCEPROP 1 LAST PATH I14
J 0
(-400 275);
DISPLAY 0.723404 (-400 275);
PAINT GREEN (-400 275);
DISPLAY INVISIBLE (-400 275);
FORCEPROP 1 LAST PART_NUMBER ALVC2G08K01
J 0
(-554 435);
DISPLAY 0.723404 (-554 435);
PAINT GREEN (-554 435);
DISPLAY INVISIBLE (-554 435);
FORCEADD NC7SB3157..1
R 2
(2025 2400);
FORCEPROP 1 LAST LOCATION U243
J 2
(2152 2615);
DISPLAY 0.723404 (2152 2615);
PAINT GREEN (2152 2615);
FORCEPROP 0 LAST $SEC 1
J 0
(2175 2775);
DISPLAY 0.680851 (2175 2775);
PAINT MONO (2175 2775);
DISPLAY INVISIBLE (2175 2775);
FORCEPROP 0 LAST CDS_SEC 1
J 0
(2175 2775);
DISPLAY 1.021277 (2175 2775);
DISPLAY INVISIBLE (2175 2775);
FORCEPROP 1 LASTPIN (1725 2300) $PN 4
J 2
(1835 2303);
DISPLAY 0.659574 (1835 2303);
PAINT MONO (1835 2303);
FORCEPROP 1 LASTPIN (2325 2300) $PN 3
J 0
(2215 2303);
DISPLAY 0.659574 (2215 2303);
PAINT MONO (2215 2303);
FORCEPROP 1 LASTPIN (2325 2400) $PN 1
J 0
(2215 2403);
DISPLAY 0.659574 (2215 2403);
PAINT MONO (2215 2403);
FORCEPROP 1 LASTPIN (2325 2350) $PN 2
J 0
(2215 2353);
DISPLAY 0.659574 (2215 2353);
PAINT MONO (2215 2353);
FORCEPROP 1 LASTPIN (1725 2400) $PN 6
J 2
(1835 2403);
DISPLAY 0.659574 (1835 2403);
PAINT MONO (1835 2403);
FORCEPROP 1 LASTPIN (1725 2350) $PN 5
J 2
(1835 2353);
DISPLAY 0.659574 (1835 2353);
PAINT MONO (1835 2353);
FORCEPROP 1 LAST MATERIAL EMPTY
J 2
(2152 2480);
DISPLAY 0.723404 (2152 2480);
PAINT RED (2152 2480);
FORCEPROP 1 LAST VALUE NC7SB3157P6X
J 2
(2150 2575);
DISPLAY 0.723404 (2150 2575);
PAINT GREEN (2150 2575);
FORCEPROP 2 LAST CDS_LIB pure_quanta
J 2
(2025 2400);
DISPLAY INVISIBLE (2025 2400);
FORCEPROP 1 LAST CDS_LMAN_SYM_OUTLINE -150,50,150,-150
J 2
(2025 2400);
DISPLAY 0.468085 (2025 2400);
PAINT GREEN (2025 2400);
DISPLAY INVISIBLE (2025 2400);
FORCEPROP 1 LAST PACK_TYPE SMLF
J 2
(2025 2150);
DISPLAY 0.723404 (2025 2150);
PAINT GREEN (2025 2150);
DISPLAY INVISIBLE (2025 2150);
FORCEPROP 0 LAST MANUF_PN NC7SB3157P6X
J 2
(2200 2775);
DISPLAY 0.808511 (2200 2775);
DISPLAY INVISIBLE (2200 2775);
FORCEPROP 0 LAST PATH I15
J 2
(2150 2775);
DISPLAY 1.021277 (2150 2775);
DISPLAY INVISIBLE (2150 2775);
FORCEPROP 1 LAST PART_NUMBER ALSB3157000
J 2
(2152 2535);
DISPLAY 0.723404 (2152 2535);
PAINT GREEN (2152 2535);
DISPLAY INVISIBLE (2152 2535);
FORCEADD NC7SB3157..1
R 2
(2025 1550);
FORCEPROP 1 LAST LOCATION U244
J 2
(2150 1755);
DISPLAY 0.723404 (2150 1755);
PAINT GREEN (2150 1755);
FORCEPROP 0 LAST $SEC 1
J 0
(2175 1925);
DISPLAY 0.680851 (2175 1925);
PAINT MONO (2175 1925);
DISPLAY INVISIBLE (2175 1925);
FORCEPROP 0 LAST CDS_SEC 1
J 0
(2175 1925);
DISPLAY 1.021277 (2175 1925);
DISPLAY INVISIBLE (2175 1925);
FORCEPROP 1 LASTPIN (1725 1450) $PN 4
J 2
(1835 1453);
DISPLAY 0.659574 (1835 1453);
PAINT MONO (1835 1453);
FORCEPROP 1 LASTPIN (2325 1450) $PN 3
J 0
(2215 1453);
DISPLAY 0.659574 (2215 1453);
PAINT MONO (2215 1453);
FORCEPROP 1 LASTPIN (2325 1550) $PN 1
J 0
(2215 1553);
DISPLAY 0.659574 (2215 1553);
PAINT MONO (2215 1553);
FORCEPROP 1 LASTPIN (2325 1500) $PN 2
J 0
(2215 1503);
DISPLAY 0.659574 (2215 1503);
PAINT MONO (2215 1503);
FORCEPROP 1 LASTPIN (1725 1550) $PN 6
J 2
(1835 1553);
DISPLAY 0.659574 (1835 1553);
PAINT MONO (1835 1553);
FORCEPROP 1 LASTPIN (1725 1500) $PN 5
J 2
(1835 1503);
DISPLAY 0.659574 (1835 1503);
PAINT MONO (1835 1503);
FORCEPROP 1 LAST MATERIAL EMPTY
J 2
(2152 1630);
DISPLAY 0.723404 (2152 1630);
PAINT RED (2152 1630);
FORCEPROP 1 LAST VALUE NC7SB3157P6X
J 2
(2148 1715);
DISPLAY 0.723404 (2148 1715);
PAINT GREEN (2148 1715);
FORCEPROP 1 LAST PACK_TYPE SMLF
J 2
(2025 1300);
DISPLAY 0.723404 (2025 1300);
PAINT GREEN (2025 1300);
DISPLAY INVISIBLE (2025 1300);
FORCEPROP 0 LAST MANUF_PN NC7SB3157P6X
J 2
(2200 1925);
DISPLAY 0.808511 (2200 1925);
DISPLAY INVISIBLE (2200 1925);
FORCEPROP 1 LAST CDS_LMAN_SYM_OUTLINE -150,50,150,-150
J 2
(2025 1550);
DISPLAY 0.468085 (2025 1550);
PAINT GREEN (2025 1550);
DISPLAY INVISIBLE (2025 1550);
FORCEPROP 2 LAST CDS_LIB pure_quanta
J 0
(2025 1550);
DISPLAY INVISIBLE (2025 1550);
FORCEPROP 0 LAST PATH I16
J 0
(2175 1925);
DISPLAY 1.021277 (2175 1925);
DISPLAY INVISIBLE (2175 1925);
FORCEPROP 1 LAST PART_NUMBER ALSB3157000
J 2
(2150 1675);
DISPLAY 0.723404 (2150 1675);
PAINT GREEN (2150 1675);
DISPLAY INVISIBLE (2150 1675);
FORCEADD NC7SB3157..1
R 2
(2200 275);
FORCEPROP 1 LAST LOCATION U246
J 2
(2325 475);
DISPLAY 0.723404 (2325 475);
PAINT GREEN (2325 475);
FORCEPROP 0 LAST $SEC 1
J 0
(2350 650);
DISPLAY 0.680851 (2350 650);
PAINT MONO (2350 650);
DISPLAY INVISIBLE (2350 650);
FORCEPROP 0 LAST CDS_SEC 1
J 0
(2350 650);
DISPLAY 1.021277 (2350 650);
DISPLAY INVISIBLE (2350 650);
FORCEPROP 1 LASTPIN (1900 175) $PN 4
J 2
(2010 178);
DISPLAY 0.659574 (2010 178);
PAINT MONO (2010 178);
FORCEPROP 1 LASTPIN (2500 175) $PN 3
J 0
(2390 178);
DISPLAY 0.659574 (2390 178);
PAINT MONO (2390 178);
FORCEPROP 1 LASTPIN (2500 275) $PN 1
J 0
(2390 278);
DISPLAY 0.659574 (2390 278);
PAINT MONO (2390 278);
FORCEPROP 1 LASTPIN (2500 225) $PN 2
J 0
(2390 228);
DISPLAY 0.659574 (2390 228);
PAINT MONO (2390 228);
FORCEPROP 1 LASTPIN (1900 275) $PN 6
J 2
(2010 278);
DISPLAY 0.659574 (2010 278);
PAINT MONO (2010 278);
FORCEPROP 1 LASTPIN (1900 225) $PN 5
J 2
(2010 228);
DISPLAY 0.659574 (2010 228);
PAINT MONO (2010 228);
FORCEPROP 1 LAST VALUE NC7SB3157P6X
J 2
(2323 435);
DISPLAY 0.723404 (2323 435);
PAINT GREEN (2323 435);
FORCEPROP 1 LAST MATERIAL EMPTY
J 2
(2327 355);
DISPLAY 0.723404 (2327 355);
PAINT RED (2327 355);
FORCEPROP 2 LAST CDS_LIB pure_quanta
J 0
(2200 275);
DISPLAY INVISIBLE (2200 275);
FORCEPROP 1 LAST CDS_LMAN_SYM_OUTLINE -150,50,150,-150
J 2
(2200 275);
DISPLAY 0.468085 (2200 275);
PAINT GREEN (2200 275);
DISPLAY INVISIBLE (2200 275);
FORCEPROP 1 LAST PACK_TYPE SMLF
J 2
(2200 25);
DISPLAY 0.723404 (2200 25);
PAINT GREEN (2200 25);
DISPLAY INVISIBLE (2200 25);
FORCEPROP 0 LAST MANUF_PN NC7SB3157P6X
J 2
(2375 650);
DISPLAY 0.808511 (2375 650);
DISPLAY INVISIBLE (2375 650);
FORCEPROP 0 LAST PATH I17
J 0
(2350 650);
DISPLAY 1.021277 (2350 650);
DISPLAY INVISIBLE (2350 650);
FORCEPROP 1 LAST PART_NUMBER ALSB3157000
J 2
(2325 395);
DISPLAY 0.723404 (2325 395);
PAINT GREEN (2325 395);
DISPLAY INVISIBLE (2325 395);
FORCEADD NC7SB3157..1
R 2
(2175 -575);
FORCEPROP 1 LAST LOCATION U245
J 2
(2300 -345);
DISPLAY 0.723404 (2300 -345);
PAINT GREEN (2300 -345);
FORCEPROP 0 LAST $SEC 1
J 0
(2325 -200);
DISPLAY 0.680851 (2325 -200);
PAINT MONO (2325 -200);
DISPLAY INVISIBLE (2325 -200);
FORCEPROP 0 LAST CDS_SEC 1
J 0
(2325 -200);
DISPLAY 1.021277 (2325 -200);
DISPLAY INVISIBLE (2325 -200);
FORCEPROP 1 LASTPIN (1875 -675) $PN 4
J 2
(1985 -672);
DISPLAY 0.659574 (1985 -672);
PAINT MONO (1985 -672);
FORCEPROP 1 LASTPIN (2475 -675) $PN 3
J 0
(2365 -672);
DISPLAY 0.659574 (2365 -672);
PAINT MONO (2365 -672);
FORCEPROP 1 LASTPIN (2475 -575) $PN 1
J 0
(2365 -572);
DISPLAY 0.659574 (2365 -572);
PAINT MONO (2365 -572);
FORCEPROP 1 LASTPIN (2475 -625) $PN 2
J 0
(2365 -622);
DISPLAY 0.659574 (2365 -622);
PAINT MONO (2365 -622);
FORCEPROP 1 LASTPIN (1875 -575) $PN 6
J 2
(1985 -572);
DISPLAY 0.659574 (1985 -572);
PAINT MONO (1985 -572);
FORCEPROP 1 LASTPIN (1875 -625) $PN 5
J 2
(1985 -622);
DISPLAY 0.659574 (1985 -622);
PAINT MONO (1985 -622);
FORCEPROP 1 LAST MATERIAL EMPTY
J 2
(2302 -495);
DISPLAY 0.723404 (2302 -495);
PAINT RED (2302 -495);
FORCEPROP 1 LAST VALUE NC7SB3157P6X
J 2
(2298 -385);
DISPLAY 0.723404 (2298 -385);
PAINT GREEN (2298 -385);
FORCEPROP 2 LAST CDS_LIB pure_quanta
J 0
(2175 -575);
DISPLAY INVISIBLE (2175 -575);
FORCEPROP 1 LAST CDS_LMAN_SYM_OUTLINE -150,50,150,-150
J 2
(2175 -575);
DISPLAY 0.468085 (2175 -575);
PAINT GREEN (2175 -575);
DISPLAY INVISIBLE (2175 -575);
FORCEPROP 1 LAST PACK_TYPE SMLF
J 2
(2175 -825);
DISPLAY 0.723404 (2175 -825);
PAINT GREEN (2175 -825);
DISPLAY INVISIBLE (2175 -825);
FORCEPROP 0 LAST MANUF_PN NC7SB3157P6X
J 2
(2350 -200);
DISPLAY 0.808511 (2350 -200);
DISPLAY INVISIBLE (2350 -200);
FORCEPROP 0 LAST PATH I18
J 0
(2325 -200);
DISPLAY 1.021277 (2325 -200);
DISPLAY INVISIBLE (2325 -200);
FORCEPROP 1 LAST PART_NUMBER ALSB3157000
J 2
(2300 -425);
DISPLAY 0.723404 (2300 -425);
PAINT GREEN (2300 -425);
DISPLAY INVISIBLE (2300 -425);
FORCEADD UNIVERSAL_GND..1
(-2375 950);
FORCEPROP 3 LASTPIN (-2375 1000) SIG_NAME GND\g
J 0
(-2365 1010);
DISPLAY 0.659574 (-2365 1010);
PAINT MONO (-2365 1010);
DISPLAY INVISIBLE (-2365 1010);
FORCEPROP 2 LAST CDS_LIB pure_quanta_power
J 0
(-2375 950);
DISPLAY INVISIBLE (-2375 950);
FORCEPROP 1 LAST HDL_POWER GND
J 1
(-2350 875);
DISPLAY 0.872340 (-2350 875);
PAINT GREEN (-2350 875);
DISPLAY INVISIBLE (-2350 875);
FORCEPROP 1 LAST PATH I19
J 0
(-2300 950);
DISPLAY 0.872340 (-2300 950);
PAINT AQUA (-2300 950);
DISPLAY INVISIBLE (-2300 950);
FORCEADD 74LVC2G08DP..2
(-2600 -150);
FORCEPROP 1 LAST LOCATION U241
J 0
(-2750 150);
DISPLAY 0.723404 (-2750 150);
PAINT GREEN (-2750 150);
FORCEPROP 0 LAST $SEC 2
J 0
(-2750 200);
DISPLAY 0.680851 (-2750 200);
PAINT MONO (-2750 200);
DISPLAY INVISIBLE (-2750 200);
FORCEPROP 0 LAST CDS_SEC 2
J 0
(-2750 200);
DISPLAY 1.021277 (-2750 200);
DISPLAY INVISIBLE (-2750 200);
FORCEPROP 0 LASTPIN (-2900 -100) $PN 5
J 2
(-2910 -90);
DISPLAY 0.680851 (-2910 -90);
PAINT MONO (-2910 -90);
FORCEPROP 0 LASTPIN (-2900 -200) $PN 6
J 2
(-2910 -190);
DISPLAY 0.680851 (-2910 -190);
PAINT MONO (-2910 -190);
FORCEPROP 0 LASTPIN (-2300 -150) $PN 3
J 0
(-2290 -140);
DISPLAY 0.680851 (-2290 -140);
PAINT MONO (-2290 -140);
FORCEPROP 1 LAST MATERIAL EMPTY
J 0
(-2754 -40);
DISPLAY 0.723404 (-2754 -40);
PAINT GREEN (-2754 -40);
FORCEPROP 2 LAST PART_TYPE SMLF
J 0
(-2750 100);
DISPLAY 0.808511 (-2750 100);
FORCEPROP 2 LAST VALUE 74LVC2G08DP
J 0
(-2750 50);
DISPLAY 0.808511 (-2750 50);
FORCEPROP 1 LAST CDS_LMAN_SYM_OUTLINE -150,100,150,-100
J 0
(-2600 -150);
DISPLAY 0.468085 (-2600 -150);
PAINT GREEN (-2600 -150);
DISPLAY INVISIBLE (-2600 -150);
FORCEPROP 1 LAST NEEDS_NO_SIZE TRUE
J 0
(-2600 -150);
DISPLAY 0.723404 (-2600 -150);
PAINT GREEN (-2600 -150);
DISPLAY INVISIBLE (-2600 -150);
FORCEPROP 2 LAST CDS_LIB pure_quanta
J 0
(-2600 -150);
DISPLAY INVISIBLE (-2600 -150);
FORCEPROP 1 LAST PATH I2
J 0
(-2600 -150);
DISPLAY 0.723404 (-2600 -150);
PAINT GREEN (-2600 -150);
DISPLAY INVISIBLE (-2600 -150);
FORCEPROP 1 LAST PART_NUMBER ALVC2G08K01
J 0
(-2754 10);
DISPLAY 0.723404 (-2754 10);
PAINT GREEN (-2754 10);
DISPLAY INVISIBLE (-2754 10);
FORCEADD UNIVERSAL_POWER..1
(-2375 1500);
FORCEPROP 3 LASTPIN (-2375 1450) SIG_NAME P3V3_AUX\g
J 0
(-2365 1460);
DISPLAY 0.659574 (-2365 1460);
PAINT MONO (-2365 1460);
DISPLAY INVISIBLE (-2365 1460);
FORCEPROP 1 LAST HDL_POWER P3V3_AUX
J 1
(-2375 1550);
DISPLAY 0.872340 (-2375 1550);
PAINT GREEN (-2375 1550);
FORCEPROP 2 LAST CDS_LIB pure_quanta_power
J 0
(-2375 1500);
DISPLAY INVISIBLE (-2375 1500);
FORCEPROP 1 LAST PATH I20
J 0
(-2325 1525);
DISPLAY 0.872340 (-2325 1525);
PAINT AQUA (-2325 1525);
DISPLAY INVISIBLE (-2325 1525);
FORCEADD Q_CAP..1
(-2375 1175);
FORCEPROP 1 LAST LOCATION C1875
J 0
(-2325 1275);
DISPLAY 0.978723 (-2325 1275);
FORCEPROP 0 LAST $SEC 1
J 0
(-2325 1325);
DISPLAY 0.680851 (-2325 1325);
PAINT MONO (-2325 1325);
DISPLAY INVISIBLE (-2325 1325);
FORCEPROP 0 LAST CDS_SEC 1
J 0
(-2325 1325);
DISPLAY 1.021277 (-2325 1325);
DISPLAY INVISIBLE (-2325 1325);
FORCEPROP 1 LASTPIN (-2375 1275) $PN 1
J 0
(-2365 1255);
DISPLAY 0.787234 (-2365 1255);
PAINT MONO (-2365 1255);
FORCEPROP 1 LASTPIN (-2375 1075) $PN 2
J 0
(-2365 1055);
DISPLAY 0.787234 (-2365 1055);
PAINT MONO (-2365 1055);
FORCEPROP 1 LAST PACK_TYPE 0402
J 0
(-2325 975);
DISPLAY 0.510638 (-2325 975);
FORCEPROP 1 LAST VALUE 0.1UF
J 0
(-2325 1225);
DISPLAY 0.510638 (-2325 1225);
FORCEPROP 1 LAST TOLERANCE 10%
J 0
(-2325 1125);
DISPLAY 0.510638 (-2325 1125);
FORCEPROP 1 LAST VOLTAGE 25V
J 0
(-2325 1175);
DISPLAY 0.510638 (-2325 1175);
FORCEPROP 1 LAST MATERIAL X7R
J 0
(-2325 1075);
DISPLAY 0.510638 (-2325 1075);
FORCEPROP 2 LAST CDS_LIB pure_quanta
J 0
(-2375 1175);
DISPLAY INVISIBLE (-2375 1175);
FORCEPROP 1 LAST PATH I21
J 0
(-2325 1325);
DISPLAY 0.978723 (-2325 1325);
PAINT WHITE (-2325 1325);
DISPLAY INVISIBLE (-2325 1325);
FORCEPROP 1 LAST PART_NUMBER CH4104K1B00
J 0
(-2325 1025);
DISPLAY 0.510638 (-2325 1025);
DISPLAY INVISIBLE (-2325 1025);
FORCEADD Q_CAP..1
(-2475 3250);
FORCEPROP 1 LAST LOCATION C1874
J 0
(-2425 3350);
DISPLAY 0.978723 (-2425 3350);
FORCEPROP 0 LAST $SEC 1
J 0
(-2425 3400);
DISPLAY 0.680851 (-2425 3400);
PAINT MONO (-2425 3400);
DISPLAY INVISIBLE (-2425 3400);
FORCEPROP 0 LAST CDS_SEC 1
J 0
(-2425 3400);
DISPLAY 1.021277 (-2425 3400);
DISPLAY INVISIBLE (-2425 3400);
FORCEPROP 1 LASTPIN (-2475 3350) $PN 1
J 0
(-2465 3330);
DISPLAY 0.787234 (-2465 3330);
PAINT MONO (-2465 3330);
FORCEPROP 1 LASTPIN (-2475 3150) $PN 2
J 0
(-2465 3130);
DISPLAY 0.787234 (-2465 3130);
PAINT MONO (-2465 3130);
FORCEPROP 1 LAST MATERIAL X7R
J 0
(-2425 3150);
DISPLAY 0.510638 (-2425 3150);
FORCEPROP 1 LAST VALUE 0.1UF
J 0
(-2425 3300);
DISPLAY 0.510638 (-2425 3300);
FORCEPROP 1 LAST PACK_TYPE 0402
J 0
(-2425 3050);
DISPLAY 0.510638 (-2425 3050);
FORCEPROP 1 LAST VOLTAGE 25V
J 0
(-2425 3250);
DISPLAY 0.510638 (-2425 3250);
FORCEPROP 1 LAST TOLERANCE 10%
J 0
(-2425 3200);
DISPLAY 0.510638 (-2425 3200);
FORCEPROP 2 LAST CDS_LIB pure_quanta
J 0
(-2475 3250);
DISPLAY INVISIBLE (-2475 3250);
FORCEPROP 1 LAST PATH I22
J 0
(-2425 3400);
DISPLAY 0.978723 (-2425 3400);
PAINT WHITE (-2425 3400);
DISPLAY INVISIBLE (-2425 3400);
FORCEPROP 1 LAST PART_NUMBER CH4104K1B00
J 0
(-2425 3100);
DISPLAY 0.510638 (-2425 3100);
DISPLAY INVISIBLE (-2425 3100);
FORCEADD UNIVERSAL_POWER..1
(-2475 3575);
FORCEPROP 3 LASTPIN (-2475 3525) SIG_NAME P3V3_AUX\g
J 0
(-2465 3535);
DISPLAY 0.659574 (-2465 3535);
PAINT MONO (-2465 3535);
DISPLAY INVISIBLE (-2465 3535);
FORCEPROP 1 LAST HDL_POWER P3V3_AUX
J 1
(-2475 3625);
DISPLAY 0.872340 (-2475 3625);
PAINT GREEN (-2475 3625);
FORCEPROP 2 LAST CDS_LIB pure_quanta_power
J 0
(-2475 3575);
DISPLAY INVISIBLE (-2475 3575);
FORCEPROP 1 LAST PATH I23
J 0
(-2425 3600);
DISPLAY 0.872340 (-2425 3600);
PAINT AQUA (-2425 3600);
DISPLAY INVISIBLE (-2425 3600);
FORCEADD UNIVERSAL_GND..1
(-2475 3025);
FORCEPROP 3 LASTPIN (-2475 3075) SIG_NAME GND\g
J 0
(-2465 3085);
DISPLAY 0.659574 (-2465 3085);
PAINT MONO (-2465 3085);
DISPLAY INVISIBLE (-2465 3085);
FORCEPROP 2 LAST CDS_LIB pure_quanta_power
J 0
(-2475 3025);
DISPLAY INVISIBLE (-2475 3025);
FORCEPROP 1 LAST HDL_POWER GND
J 1
(-2450 2950);
DISPLAY 0.872340 (-2450 2950);
PAINT GREEN (-2450 2950);
DISPLAY INVISIBLE (-2450 2950);
FORCEPROP 1 LAST PATH I24
J 0
(-2400 3025);
DISPLAY 0.872340 (-2400 3025);
PAINT AQUA (-2400 3025);
DISPLAY INVISIBLE (-2400 3025);
FORCEADD UNIVERSAL_GND..1
(-2600 2575);
FORCEPROP 3 LASTPIN (-2600 2625) SIG_NAME GND\g
J 0
(-2590 2635);
DISPLAY 0.659574 (-2590 2635);
PAINT MONO (-2590 2635);
DISPLAY INVISIBLE (-2590 2635);
FORCEPROP 2 LAST CDS_LIB pure_quanta_power
J 0
(-2600 2575);
DISPLAY INVISIBLE (-2600 2575);
FORCEPROP 1 LAST HDL_POWER GND
J 1
(-2575 2500);
DISPLAY 0.872340 (-2575 2500);
PAINT GREEN (-2575 2500);
DISPLAY INVISIBLE (-2575 2500);
FORCEPROP 1 LAST PATH I25
J 0
(-2525 2575);
DISPLAY 0.872340 (-2525 2575);
PAINT AQUA (-2525 2575);
DISPLAY INVISIBLE (-2525 2575);
FORCEADD UNIVERSAL_GND..1
(-2600 475);
FORCEPROP 3 LASTPIN (-2600 525) SIG_NAME GND\g
J 0
(-2590 535);
DISPLAY 0.659574 (-2590 535);
PAINT MONO (-2590 535);
DISPLAY INVISIBLE (-2590 535);
FORCEPROP 2 LAST CDS_LIB pure_quanta_power
J 0
(-2600 475);
DISPLAY INVISIBLE (-2600 475);
FORCEPROP 1 LAST HDL_POWER GND
J 1
(-2575 400);
DISPLAY 0.872340 (-2575 400);
PAINT GREEN (-2575 400);
DISPLAY INVISIBLE (-2575 400);
FORCEPROP 1 LAST PATH I26
J 0
(-2525 475);
DISPLAY 0.872340 (-2525 475);
PAINT AQUA (-2525 475);
DISPLAY INVISIBLE (-2525 475);
FORCEADD Q_CAP..1
(1525 575);
FORCEPROP 1 LAST LOCATION C1880
J 0
(1575 675);
DISPLAY 0.638298 (1575 675);
FORCEPROP 0 LAST $SEC 1
J 0
(1575 725);
DISPLAY 0.680851 (1575 725);
PAINT MONO (1575 725);
DISPLAY INVISIBLE (1575 725);
FORCEPROP 0 LAST CDS_SEC 1
J 0
(1575 725);
DISPLAY 1.021277 (1575 725);
DISPLAY INVISIBLE (1575 725);
FORCEPROP 1 LASTPIN (1525 675) $PN 1
J 0
(1535 655);
DISPLAY 0.787234 (1535 655);
PAINT MONO (1535 655);
FORCEPROP 1 LASTPIN (1525 475) $PN 2
J 0
(1535 455);
DISPLAY 0.787234 (1535 455);
PAINT MONO (1535 455);
FORCEPROP 1 LAST PACK_TYPE 0402
J 0
(1575 375);
DISPLAY 0.510638 (1575 375);
FORCEPROP 1 LAST VALUE 0.1UF
J 0
(1575 625);
DISPLAY 0.510638 (1575 625);
FORCEPROP 1 LAST VOLTAGE 25V
J 0
(1575 575);
DISPLAY 0.510638 (1575 575);
FORCEPROP 1 LAST TOLERANCE 10%
J 0
(1575 525);
DISPLAY 0.510638 (1575 525);
FORCEPROP 1 LAST MATERIAL X7R
J 0
(1575 475);
DISPLAY 0.510638 (1575 475);
FORCEPROP 2 LAST CDS_LIB pure_quanta
J 0
(1525 575);
DISPLAY INVISIBLE (1525 575);
FORCEPROP 1 LAST PATH I27
J 0
(1575 725);
DISPLAY 0.978723 (1575 725);
PAINT WHITE (1575 725);
DISPLAY INVISIBLE (1575 725);
FORCEPROP 1 LAST PART_NUMBER CH4104K1B00
J 0
(1575 425);
DISPLAY 0.510638 (1575 425);
DISPLAY INVISIBLE (1575 425);
FORCEADD UNIVERSAL_GND..1
(1525 350);
FORCEPROP 3 LASTPIN (1525 400) SIG_NAME GND\g
J 0
(1535 410);
DISPLAY 0.659574 (1535 410);
PAINT MONO (1535 410);
DISPLAY INVISIBLE (1535 410);
FORCEPROP 2 LAST CDS_LIB pure_quanta_power
J 0
(1525 350);
DISPLAY INVISIBLE (1525 350);
FORCEPROP 1 LAST HDL_POWER GND
J 1
(1550 275);
DISPLAY 0.872340 (1550 275);
PAINT GREEN (1550 275);
DISPLAY INVISIBLE (1550 275);
FORCEPROP 1 LAST PATH I28
J 0
(1600 350);
DISPLAY 0.872340 (1600 350);
PAINT AQUA (1600 350);
DISPLAY INVISIBLE (1600 350);
FORCEADD UNIVERSAL_POWER..1
(1525 900);
FORCEPROP 3 LASTPIN (1525 850) SIG_NAME P3V3_AUX\g
J 0
(1535 860);
DISPLAY 0.659574 (1535 860);
PAINT MONO (1535 860);
DISPLAY INVISIBLE (1535 860);
FORCEPROP 1 LAST HDL_POWER P3V3_AUX
J 1
(1525 950);
DISPLAY 0.872340 (1525 950);
PAINT GREEN (1525 950);
FORCEPROP 2 LAST CDS_LIB pure_quanta_power
J 0
(1525 900);
DISPLAY INVISIBLE (1525 900);
FORCEPROP 1 LAST PATH I29
J 0
(1575 925);
DISPLAY 0.872340 (1575 925);
PAINT AQUA (1575 925);
DISPLAY INVISIBLE (1575 925);
FORCEADD OFFPAGE..1
(-3600 800);
FORCEPROP 2 LAST $XR1 140 
J 0
(-4002 800);
DISPLAY 0.638298 (-4002 800);
PAINT MONO (-4002 800);
FORCEPROP 2 LAST $XR0 137 
J 0
(-3882 800);
DISPLAY 0.638298 (-3882 800);
PAINT MONO (-3882 800);
FORCEPROP 2 LAST CDS_LIB standard
J 0
(-3600 800);
PAINT MONO (-3600 800);
DISPLAY INVISIBLE (-3600 800);
FORCEPROP 1 LAST OFFPAGE TRUE
J 0
(-3275 675);
DISPLAY 0.872340 (-3275 675);
PAINT GREEN (-3275 675);
DISPLAY INVISIBLE (-3275 675);
FORCEPROP 1 LAST COMMENT_BODY TRUE
J 0
(-3475 700);
DISPLAY 0.872340 (-3475 700);
PAINT GREEN (-3475 700);
DISPLAY INVISIBLE (-3475 700);
FORCEPROP 2 LAST PATH I3
J 0
(-3875 850);
DISPLAY 1.021277 (-3875 850);
DISPLAY INVISIBLE (-3875 850);
FORCEADD UNIVERSAL_POWER..1
(1525 25);
FORCEPROP 3 LASTPIN (1525 -25) SIG_NAME P3V3_AUX\g
J 0
(1535 -15);
DISPLAY 0.659574 (1535 -15);
PAINT MONO (1535 -15);
DISPLAY INVISIBLE (1535 -15);
FORCEPROP 1 LAST HDL_POWER P3V3_AUX
J 1
(1525 75);
DISPLAY 0.872340 (1525 75);
PAINT GREEN (1525 75);
FORCEPROP 2 LAST CDS_LIB pure_quanta_power
J 0
(1525 25);
DISPLAY INVISIBLE (1525 25);
FORCEPROP 1 LAST PATH I30
J 0
(1575 50);
DISPLAY 0.872340 (1575 50);
PAINT AQUA (1575 50);
DISPLAY INVISIBLE (1575 50);
FORCEADD Q_CAP..1
(1525 -250);
FORCEPROP 1 LAST LOCATION C1879
J 0
(1575 -150);
DISPLAY 0.638298 (1575 -150);
FORCEPROP 0 LAST $SEC 1
J 0
(1575 -100);
DISPLAY 0.680851 (1575 -100);
PAINT MONO (1575 -100);
DISPLAY INVISIBLE (1575 -100);
FORCEPROP 0 LAST CDS_SEC 1
J 0
(1575 -100);
DISPLAY 1.021277 (1575 -100);
DISPLAY INVISIBLE (1575 -100);
FORCEPROP 1 LASTPIN (1525 -150) $PN 1
J 0
(1535 -170);
DISPLAY 0.787234 (1535 -170);
PAINT MONO (1535 -170);
FORCEPROP 1 LASTPIN (1525 -350) $PN 2
J 0
(1535 -370);
DISPLAY 0.787234 (1535 -370);
PAINT MONO (1535 -370);
FORCEPROP 1 LAST VALUE 0.1UF
J 0
(1575 -200);
DISPLAY 0.510638 (1575 -200);
FORCEPROP 1 LAST TOLERANCE 10%
J 0
(1575 -300);
DISPLAY 0.510638 (1575 -300);
FORCEPROP 1 LAST MATERIAL X7R
J 0
(1575 -350);
DISPLAY 0.510638 (1575 -350);
FORCEPROP 1 LAST PACK_TYPE 0402
J 0
(1575 -450);
DISPLAY 0.510638 (1575 -450);
FORCEPROP 1 LAST VOLTAGE 25V
J 0
(1575 -250);
DISPLAY 0.510638 (1575 -250);
FORCEPROP 2 LAST CDS_LIB pure_quanta
J 0
(1525 -250);
DISPLAY INVISIBLE (1525 -250);
FORCEPROP 1 LAST PATH I31
J 0
(1575 -100);
DISPLAY 0.978723 (1575 -100);
PAINT WHITE (1575 -100);
DISPLAY INVISIBLE (1575 -100);
FORCEPROP 1 LAST PART_NUMBER CH4104K1B00
J 0
(1575 -400);
DISPLAY 0.510638 (1575 -400);
DISPLAY INVISIBLE (1575 -400);
FORCEADD UNIVERSAL_GND..1
(1525 -475);
FORCEPROP 3 LASTPIN (1525 -425) SIG_NAME GND\g
J 0
(1535 -415);
DISPLAY 0.659574 (1535 -415);
PAINT MONO (1535 -415);
DISPLAY INVISIBLE (1535 -415);
FORCEPROP 2 LAST CDS_LIB pure_quanta_power
J 0
(1525 -475);
DISPLAY INVISIBLE (1525 -475);
FORCEPROP 1 LAST HDL_POWER GND
J 1
(1550 -550);
DISPLAY 0.872340 (1550 -550);
PAINT GREEN (1550 -550);
DISPLAY INVISIBLE (1550 -550);
FORCEPROP 1 LAST PATH I32
J 0
(1600 -475);
DISPLAY 0.872340 (1600 -475);
PAINT AQUA (1600 -475);
DISPLAY INVISIBLE (1600 -475);
FORCEADD UNIVERSAL_POWER..1
(1325 3100);
FORCEPROP 3 LASTPIN (1325 3050) SIG_NAME P3V3_AUX\g
J 0
(1335 3060);
DISPLAY 0.659574 (1335 3060);
PAINT MONO (1335 3060);
DISPLAY INVISIBLE (1335 3060);
FORCEPROP 1 LAST HDL_POWER P3V3_AUX
J 1
(1325 3150);
DISPLAY 0.872340 (1325 3150);
PAINT GREEN (1325 3150);
FORCEPROP 2 LAST CDS_LIB pure_quanta_power
J 0
(1325 3100);
DISPLAY INVISIBLE (1325 3100);
FORCEPROP 1 LAST PATH I33
J 0
(1375 3125);
DISPLAY 0.872340 (1375 3125);
PAINT AQUA (1375 3125);
DISPLAY INVISIBLE (1375 3125);
FORCEADD Q_CAP..1
(1325 2775);
FORCEPROP 1 LAST LOCATION C1877
J 0
(1375 2875);
DISPLAY 0.638298 (1375 2875);
FORCEPROP 0 LAST $SEC 1
J 0
(1375 2925);
DISPLAY 0.680851 (1375 2925);
PAINT MONO (1375 2925);
DISPLAY INVISIBLE (1375 2925);
FORCEPROP 0 LAST CDS_SEC 1
J 0
(1375 2925);
DISPLAY 1.021277 (1375 2925);
DISPLAY INVISIBLE (1375 2925);
FORCEPROP 1 LASTPIN (1325 2875) $PN 1
J 0
(1335 2855);
DISPLAY 0.787234 (1335 2855);
PAINT MONO (1335 2855);
FORCEPROP 1 LASTPIN (1325 2675) $PN 2
J 0
(1335 2655);
DISPLAY 0.787234 (1335 2655);
PAINT MONO (1335 2655);
FORCEPROP 1 LAST PACK_TYPE 0402
J 0
(1375 2575);
DISPLAY 0.510638 (1375 2575);
FORCEPROP 1 LAST VALUE 0.1UF
J 0
(1375 2825);
DISPLAY 0.510638 (1375 2825);
FORCEPROP 1 LAST VOLTAGE 25V
J 0
(1375 2775);
DISPLAY 0.510638 (1375 2775);
FORCEPROP 1 LAST TOLERANCE 10%
J 0
(1375 2725);
DISPLAY 0.510638 (1375 2725);
FORCEPROP 1 LAST MATERIAL X7R
J 0
(1375 2675);
DISPLAY 0.510638 (1375 2675);
FORCEPROP 2 LAST CDS_LIB pure_quanta
J 0
(1325 2775);
DISPLAY INVISIBLE (1325 2775);
FORCEPROP 1 LAST PATH I34
J 0
(1375 2925);
DISPLAY 0.978723 (1375 2925);
PAINT WHITE (1375 2925);
DISPLAY INVISIBLE (1375 2925);
FORCEPROP 1 LAST PART_NUMBER CH4104K1B00
J 0
(1375 2625);
DISPLAY 0.510638 (1375 2625);
DISPLAY INVISIBLE (1375 2625);
FORCEADD UNIVERSAL_GND..1
(1325 2550);
FORCEPROP 3 LASTPIN (1325 2600) SIG_NAME GND\g
J 0
(1335 2610);
DISPLAY 0.659574 (1335 2610);
PAINT MONO (1335 2610);
DISPLAY INVISIBLE (1335 2610);
FORCEPROP 2 LAST CDS_LIB pure_quanta_power
J 0
(1325 2550);
DISPLAY INVISIBLE (1325 2550);
FORCEPROP 1 LAST HDL_POWER GND
J 1
(1350 2475);
DISPLAY 0.872340 (1350 2475);
PAINT GREEN (1350 2475);
DISPLAY INVISIBLE (1350 2475);
FORCEPROP 1 LAST PATH I35
J 0
(1400 2550);
DISPLAY 0.872340 (1400 2550);
PAINT AQUA (1400 2550);
DISPLAY INVISIBLE (1400 2550);
FORCEADD UNIVERSAL_GND..1
(1350 1700);
FORCEPROP 3 LASTPIN (1350 1750) SIG_NAME GND\g
J 0
(1360 1760);
DISPLAY 0.659574 (1360 1760);
PAINT MONO (1360 1760);
DISPLAY INVISIBLE (1360 1760);
FORCEPROP 2 LAST CDS_LIB pure_quanta_power
J 0
(1350 1700);
DISPLAY INVISIBLE (1350 1700);
FORCEPROP 1 LAST HDL_POWER GND
J 1
(1375 1625);
DISPLAY 0.872340 (1375 1625);
PAINT GREEN (1375 1625);
DISPLAY INVISIBLE (1375 1625);
FORCEPROP 1 LAST PATH I36
J 0
(1425 1700);
DISPLAY 0.872340 (1425 1700);
PAINT AQUA (1425 1700);
DISPLAY INVISIBLE (1425 1700);
FORCEADD Q_CAP..1
(1350 1925);
FORCEPROP 1 LAST LOCATION C1878
J 0
(1400 2025);
DISPLAY 0.638298 (1400 2025);
FORCEPROP 0 LAST $SEC 1
J 0
(1400 2075);
DISPLAY 0.680851 (1400 2075);
PAINT MONO (1400 2075);
DISPLAY INVISIBLE (1400 2075);
FORCEPROP 0 LAST CDS_SEC 1
J 0
(1400 2075);
DISPLAY 1.021277 (1400 2075);
DISPLAY INVISIBLE (1400 2075);
FORCEPROP 1 LASTPIN (1350 2025) $PN 1
J 0
(1360 2005);
DISPLAY 0.787234 (1360 2005);
PAINT MONO (1360 2005);
FORCEPROP 1 LASTPIN (1350 1825) $PN 2
J 0
(1360 1805);
DISPLAY 0.787234 (1360 1805);
PAINT MONO (1360 1805);
FORCEPROP 1 LAST VALUE 0.1UF
J 0
(1400 1975);
DISPLAY 0.510638 (1400 1975);
FORCEPROP 1 LAST TOLERANCE 10%
J 0
(1400 1875);
DISPLAY 0.510638 (1400 1875);
FORCEPROP 1 LAST MATERIAL X7R
J 0
(1400 1825);
DISPLAY 0.510638 (1400 1825);
FORCEPROP 1 LAST PACK_TYPE 0402
J 0
(1400 1725);
DISPLAY 0.510638 (1400 1725);
FORCEPROP 1 LAST VOLTAGE 25V
J 0
(1400 1925);
DISPLAY 0.510638 (1400 1925);
FORCEPROP 2 LAST CDS_LIB pure_quanta
J 0
(1350 1925);
DISPLAY INVISIBLE (1350 1925);
FORCEPROP 1 LAST PATH I37
J 0
(1400 2075);
DISPLAY 0.978723 (1400 2075);
PAINT WHITE (1400 2075);
DISPLAY INVISIBLE (1400 2075);
FORCEPROP 1 LAST PART_NUMBER CH4104K1B00
J 0
(1400 1775);
DISPLAY 0.510638 (1400 1775);
DISPLAY INVISIBLE (1400 1775);
FORCEADD UNIVERSAL_POWER..1
(1350 2175);
FORCEPROP 3 LASTPIN (1350 2125) SIG_NAME P3V3_AUX\g
J 0
(1360 2135);
DISPLAY 0.659574 (1360 2135);
PAINT MONO (1360 2135);
DISPLAY INVISIBLE (1360 2135);
FORCEPROP 1 LAST HDL_POWER P3V3_AUX
J 1
(1350 2225);
DISPLAY 0.872340 (1350 2225);
PAINT GREEN (1350 2225);
FORCEPROP 2 LAST CDS_LIB pure_quanta_power
J 0
(1350 2175);
DISPLAY INVISIBLE (1350 2175);
FORCEPROP 1 LAST PATH I38
J 0
(1400 2200);
DISPLAY 0.872340 (1400 2200);
PAINT AQUA (1400 2200);
DISPLAY INVISIBLE (1400 2200);
FORCEADD UNIVERSAL_GND..1
(-325 2625);
FORCEPROP 3 LASTPIN (-325 2675) SIG_NAME GND\g
J 0
(-315 2685);
DISPLAY 0.659574 (-315 2685);
PAINT MONO (-315 2685);
DISPLAY INVISIBLE (-315 2685);
FORCEPROP 2 LAST CDS_LIB pure_quanta_power
J 0
(-325 2625);
DISPLAY INVISIBLE (-325 2625);
FORCEPROP 1 LAST HDL_POWER GND
J 1
(-300 2550);
DISPLAY 0.872340 (-300 2550);
PAINT GREEN (-300 2550);
DISPLAY INVISIBLE (-300 2550);
FORCEPROP 1 LAST PATH I39
J 0
(-250 2625);
DISPLAY 0.872340 (-250 2625);
PAINT AQUA (-250 2625);
DISPLAY INVISIBLE (-250 2625);
FORCEADD OFFPAGE..1
(-3600 700);
FORCEPROP 2 LAST $XR1 140 
J 0
(-4002 700);
DISPLAY 0.638298 (-4002 700);
PAINT MONO (-4002 700);
FORCEPROP 2 LAST $XR0 137 
J 0
(-3882 700);
DISPLAY 0.638298 (-3882 700);
PAINT MONO (-3882 700);
FORCEPROP 2 LAST CDS_LIB standard
J 0
(-3600 700);
PAINT MONO (-3600 700);
DISPLAY INVISIBLE (-3600 700);
FORCEPROP 1 LAST OFFPAGE TRUE
J 0
(-3275 575);
DISPLAY 0.872340 (-3275 575);
PAINT GREEN (-3275 575);
DISPLAY INVISIBLE (-3275 575);
FORCEPROP 1 LAST COMMENT_BODY TRUE
J 0
(-3475 600);
DISPLAY 0.872340 (-3475 600);
PAINT GREEN (-3475 600);
DISPLAY INVISIBLE (-3475 600);
FORCEPROP 2 LAST PATH I4
J 0
(-3875 750);
DISPLAY 1.021277 (-3875 750);
DISPLAY INVISIBLE (-3875 750);
FORCEADD UNIVERSAL_POWER..1
(-325 3175);
FORCEPROP 3 LASTPIN (-325 3125) SIG_NAME P3V3_AUX\g
J 0
(-315 3135);
DISPLAY 0.659574 (-315 3135);
PAINT MONO (-315 3135);
DISPLAY INVISIBLE (-315 3135);
FORCEPROP 1 LAST HDL_POWER P3V3_AUX
J 1
(-325 3225);
DISPLAY 0.872340 (-325 3225);
PAINT GREEN (-325 3225);
FORCEPROP 2 LAST CDS_LIB pure_quanta_power
J 0
(-325 3175);
DISPLAY INVISIBLE (-325 3175);
FORCEPROP 1 LAST PATH I40
J 0
(-275 3200);
DISPLAY 0.872340 (-275 3200);
PAINT AQUA (-275 3200);
DISPLAY INVISIBLE (-275 3200);
FORCEADD Q_CAP..1
(-325 2850);
FORCEPROP 1 LAST LOCATION C1876
J 0
(-275 2950);
DISPLAY 0.978723 (-275 2950);
FORCEPROP 0 LAST $SEC 1
J 0
(-275 3000);
DISPLAY 0.680851 (-275 3000);
PAINT MONO (-275 3000);
DISPLAY INVISIBLE (-275 3000);
FORCEPROP 0 LAST CDS_SEC 1
J 0
(-275 3000);
DISPLAY 1.021277 (-275 3000);
DISPLAY INVISIBLE (-275 3000);
FORCEPROP 1 LASTPIN (-325 2950) $PN 1
J 0
(-315 2930);
DISPLAY 0.787234 (-315 2930);
PAINT MONO (-315 2930);
FORCEPROP 1 LASTPIN (-325 2750) $PN 2
J 0
(-315 2730);
DISPLAY 0.787234 (-315 2730);
PAINT MONO (-315 2730);
FORCEPROP 1 LAST MATERIAL X7R
J 0
(-275 2750);
DISPLAY 0.510638 (-275 2750);
FORCEPROP 1 LAST PACK_TYPE 0402
J 0
(-275 2650);
DISPLAY 0.510638 (-275 2650);
FORCEPROP 1 LAST VALUE 0.1UF
J 0
(-275 2900);
DISPLAY 0.510638 (-275 2900);
FORCEPROP 1 LAST TOLERANCE 10%
J 0
(-275 2800);
DISPLAY 0.510638 (-275 2800);
FORCEPROP 1 LAST VOLTAGE 25V
J 0
(-275 2850);
DISPLAY 0.510638 (-275 2850);
FORCEPROP 2 LAST CDS_LIB pure_quanta
J 0
(-325 2850);
DISPLAY INVISIBLE (-325 2850);
FORCEPROP 1 LAST PATH I41
J 0
(-275 3000);
DISPLAY 0.978723 (-275 3000);
PAINT WHITE (-275 3000);
DISPLAY INVISIBLE (-275 3000);
FORCEPROP 1 LAST PART_NUMBER CH4104K1B00
J 0
(-275 2700);
DISPLAY 0.510638 (-275 2700);
DISPLAY INVISIBLE (-275 2700);
FORCEADD UNIVERSAL_GND..1
(-400 2125);
FORCEPROP 3 LASTPIN (-400 2175) SIG_NAME GND\g
J 0
(-390 2185);
DISPLAY 0.659574 (-390 2185);
PAINT MONO (-390 2185);
DISPLAY INVISIBLE (-390 2185);
FORCEPROP 2 LAST CDS_LIB pure_quanta_power
J 0
(-400 2125);
DISPLAY INVISIBLE (-400 2125);
FORCEPROP 1 LAST HDL_POWER GND
J 1
(-375 2050);
DISPLAY 0.872340 (-375 2050);
PAINT GREEN (-375 2050);
DISPLAY INVISIBLE (-375 2050);
FORCEPROP 1 LAST PATH I42
J 0
(-325 2125);
DISPLAY 0.872340 (-325 2125);
PAINT AQUA (-325 2125);
DISPLAY INVISIBLE (-325 2125);
FORCEADD Q_RES..1
(825 2400);
FORCEPROP 1 LAST LOCATION R3303
J 0
(625 2400);
DISPLAY 0.638298 (625 2400);
FORCEPROP 0 LAST $SEC 1
J 0
(775 2525);
DISPLAY 0.680851 (775 2525);
PAINT MONO (775 2525);
DISPLAY INVISIBLE (775 2525);
FORCEPROP 0 LAST CDS_SEC 1
J 0
(775 2525);
DISPLAY 1.021277 (775 2525);
DISPLAY INVISIBLE (775 2525);
FORCEPROP 1 LASTPIN (725 2400) $PN 1
J 0
(737 2412);
DISPLAY 0.787234 (737 2412);
PAINT MONO (737 2412);
FORCEPROP 1 LASTPIN (925 2400) $PN 2
J 0
(887 2412);
DISPLAY 0.787234 (887 2412);
PAINT MONO (887 2412);
FORCEPROP 1 LAST PACK_TYPE 0402LF
J 0
(775 2500);
DISPLAY 0.404255 (775 2500);
FORCEPROP 1 LAST MATERIAL CHIP
J 0
(775 2475);
DISPLAY 0.404255 (775 2475);
FORCEPROP 1 LAST VALUE 0
J 2
(975 2400);
DISPLAY 0.510638 (975 2400);
FORCEPROP 1 LAST WATTAGE 1/16W
J 2
(1000 2475);
DISPLAY 0.404255 (1000 2475);
FORCEPROP 1 LAST TOLERANCE 5%
J 0
(1000 2400);
DISPLAY 0.510638 (1000 2400);
FORCEPROP 2 LAST CDS_LIB pure_quanta
J 0
(825 2400);
DISPLAY INVISIBLE (825 2400);
FORCEPROP 1 LAST PATH I44
J 0
(775 2550);
DISPLAY 0.978723 (775 2550);
PAINT WHITE (775 2550);
DISPLAY INVISIBLE (775 2550);
FORCEPROP 1 LAST PART_NUMBER CS00002JB13
J 0
(775 2450);
DISPLAY 0.404255 (775 2450);
DISPLAY INVISIBLE (775 2450);
FORCEADD Q_RES..1
(625 1550);
FORCEPROP 1 LAST LOCATION R3304
J 0
(425 1550);
DISPLAY 0.638298 (425 1550);
FORCEPROP 0 LAST $SEC 1
J 0
(575 1675);
DISPLAY 0.680851 (575 1675);
PAINT MONO (575 1675);
DISPLAY INVISIBLE (575 1675);
FORCEPROP 0 LAST CDS_SEC 1
J 0
(575 1675);
DISPLAY 1.021277 (575 1675);
DISPLAY INVISIBLE (575 1675);
FORCEPROP 1 LASTPIN (525 1550) $PN 1
J 0
(537 1562);
DISPLAY 0.787234 (537 1562);
PAINT MONO (537 1562);
FORCEPROP 1 LASTPIN (725 1550) $PN 2
J 0
(687 1562);
DISPLAY 0.787234 (687 1562);
PAINT MONO (687 1562);
FORCEPROP 1 LAST MATERIAL CHIP
J 0
(575 1625);
DISPLAY 0.404255 (575 1625);
FORCEPROP 1 LAST PACK_TYPE 0402LF
J 0
(575 1650);
DISPLAY 0.404255 (575 1650);
FORCEPROP 1 LAST WATTAGE 1/16W
J 2
(800 1625);
DISPLAY 0.404255 (800 1625);
FORCEPROP 1 LAST TOLERANCE 5%
J 0
(800 1550);
DISPLAY 0.510638 (800 1550);
FORCEPROP 1 LAST VALUE 0
J 2
(775 1550);
DISPLAY 0.510638 (775 1550);
FORCEPROP 2 LAST CDS_LIB pure_quanta
J 0
(625 1550);
DISPLAY INVISIBLE (625 1550);
FORCEPROP 1 LAST PATH I45
J 0
(575 1700);
DISPLAY 0.978723 (575 1700);
PAINT WHITE (575 1700);
DISPLAY INVISIBLE (575 1700);
FORCEPROP 1 LAST PART_NUMBER CS00002JB13
J 0
(575 1600);
DISPLAY 0.404255 (575 1600);
DISPLAY INVISIBLE (575 1600);
FORCEADD Q_RES..1
(825 275);
FORCEPROP 1 LAST LOCATION R3308
J 0
(625 275);
DISPLAY 0.510638 (625 275);
FORCEPROP 0 LAST $SEC 1
J 0
(775 400);
DISPLAY 0.680851 (775 400);
PAINT MONO (775 400);
DISPLAY INVISIBLE (775 400);
FORCEPROP 0 LAST CDS_SEC 1
J 0
(775 400);
DISPLAY 1.021277 (775 400);
DISPLAY INVISIBLE (775 400);
FORCEPROP 1 LASTPIN (725 275) $PN 1
J 0
(737 287);
DISPLAY 0.787234 (737 287);
PAINT MONO (737 287);
FORCEPROP 1 LASTPIN (925 275) $PN 2
J 0
(887 287);
DISPLAY 0.787234 (887 287);
PAINT MONO (887 287);
FORCEPROP 1 LAST MATERIAL CHIP
J 0
(775 350);
DISPLAY 0.404255 (775 350);
FORCEPROP 1 LAST PACK_TYPE 0402LF
J 0
(775 375);
DISPLAY 0.404255 (775 375);
FORCEPROP 1 LAST TOLERANCE 5%
J 0
(1000 275);
DISPLAY 0.510638 (1000 275);
FORCEPROP 1 LAST WATTAGE 1/16W
J 2
(1000 350);
DISPLAY 0.404255 (1000 350);
FORCEPROP 1 LAST VALUE 0
J 2
(975 275);
DISPLAY 0.510638 (975 275);
FORCEPROP 2 LAST CDS_LIB pure_quanta
J 0
(825 275);
DISPLAY INVISIBLE (825 275);
FORCEPROP 1 LAST PATH I46
J 0
(775 425);
DISPLAY 0.978723 (775 425);
PAINT WHITE (775 425);
DISPLAY INVISIBLE (775 425);
FORCEPROP 1 LAST PART_NUMBER CS00002JB13
J 0
(775 325);
DISPLAY 0.404255 (775 325);
DISPLAY INVISIBLE (775 325);
FORCEADD Q_RES..1
(800 -575);
FORCEPROP 1 LAST LOCATION R3306
J 0
(625 -575);
DISPLAY 0.510638 (625 -575);
FORCEPROP 0 LAST $SEC 1
J 0
(750 -450);
DISPLAY 0.680851 (750 -450);
PAINT MONO (750 -450);
DISPLAY INVISIBLE (750 -450);
FORCEPROP 0 LAST CDS_SEC 1
J 0
(750 -450);
DISPLAY 1.021277 (750 -450);
DISPLAY INVISIBLE (750 -450);
FORCEPROP 1 LASTPIN (700 -575) $PN 1
J 0
(712 -563);
DISPLAY 0.787234 (712 -563);
PAINT MONO (712 -563);
FORCEPROP 1 LASTPIN (900 -575) $PN 2
J 0
(862 -563);
DISPLAY 0.787234 (862 -563);
PAINT MONO (862 -563);
FORCEPROP 1 LAST VALUE 0
J 2
(950 -575);
DISPLAY 0.510638 (950 -575);
FORCEPROP 1 LAST PACK_TYPE 0402LF
J 0
(750 -475);
DISPLAY 0.404255 (750 -475);
FORCEPROP 1 LAST MATERIAL CHIP
J 0
(750 -500);
DISPLAY 0.404255 (750 -500);
FORCEPROP 1 LAST TOLERANCE 5%
J 0
(975 -575);
DISPLAY 0.510638 (975 -575);
FORCEPROP 1 LAST WATTAGE 1/16W
J 2
(975 -500);
DISPLAY 0.404255 (975 -500);
FORCEPROP 2 LAST CDS_LIB pure_quanta
J 0
(800 -575);
DISPLAY INVISIBLE (800 -575);
FORCEPROP 1 LAST PATH I47
J 0
(750 -425);
DISPLAY 0.978723 (750 -425);
PAINT WHITE (750 -425);
DISPLAY INVISIBLE (750 -425);
FORCEPROP 1 LAST PART_NUMBER CS00002JB13
J 0
(750 -525);
DISPLAY 0.404255 (750 -525);
DISPLAY INVISIBLE (750 -525);
FORCEADD OFFPAGE..1
R 2
(3100 1450);
FORCEPROP 2 LAST $XR0 132 
J 0
(3286 1450);
DISPLAY 0.638298 (3286 1450);
PAINT MONO (3286 1450);
FORCEPROP 2 LAST CDS_LIB standard
J 2
(3100 1450);
DISPLAY INVISIBLE (3100 1450);
FORCEPROP 1 LAST OFFPAGE TRUE
J 2
(2775 1325);
DISPLAY 0.872340 (2775 1325);
PAINT GREEN (2775 1325);
DISPLAY INVISIBLE (2775 1325);
FORCEPROP 1 LAST COMMENT_BODY TRUE
J 2
(2975 1350);
DISPLAY 0.872340 (2975 1350);
PAINT GREEN (2975 1350);
DISPLAY INVISIBLE (2975 1350);
FORCEPROP 2 LAST PATH I48
J 0
(3275 1525);
DISPLAY 1.021277 (3275 1525);
DISPLAY INVISIBLE (3275 1525);
FORCEADD OFFPAGE..2
R 2
(-350 1450);
FORCEPROP 2 LAST $XR0 143 
J 0
(-605 1450);
DISPLAY 0.638298 (-605 1450);
PAINT MONO (-605 1450);
FORCEPROP 2 LAST CDS_LIB standard
J 2
(-350 1450);
DISPLAY INVISIBLE (-350 1450);
FORCEPROP 1 LAST OFFPAGE TRUE
J 2
(-675 1325);
DISPLAY 0.872340 (-675 1325);
PAINT GREEN (-675 1325);
DISPLAY INVISIBLE (-675 1325);
FORCEPROP 1 LAST COMMENT_BODY TRUE
J 2
(-305 1355);
DISPLAY 0.872340 (-305 1355);
PAINT GREEN (-305 1355);
DISPLAY INVISIBLE (-305 1355);
FORCEPROP 2 LAST PATH I49
J 2
(-525 1525);
DISPLAY 1.021277 (-525 1525);
DISPLAY INVISIBLE (-525 1525);
FORCEADD OFFPAGE..1
(-3600 -200);
FORCEPROP 2 LAST $XR1 140 
J 0
(-4002 -200);
DISPLAY 0.638298 (-4002 -200);
PAINT MONO (-4002 -200);
FORCEPROP 2 LAST $XR0 137 
J 0
(-3882 -200);
DISPLAY 0.638298 (-3882 -200);
PAINT MONO (-3882 -200);
FORCEPROP 2 LAST CDS_LIB standard
J 0
(-3600 -200);
PAINT MONO (-3600 -200);
DISPLAY INVISIBLE (-3600 -200);
FORCEPROP 1 LAST OFFPAGE TRUE
J 0
(-3275 -325);
DISPLAY 0.872340 (-3275 -325);
PAINT GREEN (-3275 -325);
DISPLAY INVISIBLE (-3275 -325);
FORCEPROP 1 LAST COMMENT_BODY TRUE
J 0
(-3475 -300);
DISPLAY 0.872340 (-3475 -300);
PAINT GREEN (-3475 -300);
DISPLAY INVISIBLE (-3475 -300);
FORCEPROP 2 LAST PATH I5
J 0
(-3875 -150);
DISPLAY 1.021277 (-3875 -150);
DISPLAY INVISIBLE (-3875 -150);
FORCEADD Q_RES..1
(625 1450);
FORCEPROP 1 LAST LOCATION R3305
J 0
(425 1450);
DISPLAY 0.638298 (425 1450);
FORCEPROP 0 LAST $SEC 1
J 0
(575 1525);
DISPLAY 0.680851 (575 1525);
PAINT MONO (575 1525);
DISPLAY INVISIBLE (575 1525);
FORCEPROP 0 LAST CDS_SEC 1
J 0
(575 1525);
DISPLAY 1.021277 (575 1525);
DISPLAY INVISIBLE (575 1525);
FORCEPROP 1 LASTPIN (525 1450) $PN 1
J 0
(537 1462);
DISPLAY 0.787234 (537 1462);
PAINT MONO (537 1462);
FORCEPROP 1 LASTPIN (725 1450) $PN 2
J 0
(687 1462);
DISPLAY 0.787234 (687 1462);
PAINT MONO (687 1462);
FORCEPROP 1 LAST MATERIAL CHIP
J 0
(525 1350);
DISPLAY 0.404255 (525 1350);
FORCEPROP 1 LAST VALUE 0
J 2
(775 1450);
DISPLAY 0.510638 (775 1450);
FORCEPROP 1 LAST TOLERANCE 5%
J 0
(800 1450);
DISPLAY 0.510638 (800 1450);
FORCEPROP 1 LAST WATTAGE 1/16W
J 2
(750 1400);
DISPLAY 0.404255 (750 1400);
FORCEPROP 1 LAST PACK_TYPE 0402LF
J 0
(525 1400);
DISPLAY 0.404255 (525 1400);
FORCEPROP 2 LAST CDS_LIB pure_quanta
J 0
(625 1450);
DISPLAY INVISIBLE (625 1450);
FORCEPROP 1 LAST PATH I50
J 0
(575 1600);
DISPLAY 0.978723 (575 1600);
PAINT WHITE (575 1600);
DISPLAY INVISIBLE (575 1600);
FORCEPROP 1 LAST PART_NUMBER CS00002JB13
J 0
(525 1375);
DISPLAY 0.404255 (525 1375);
DISPLAY INVISIBLE (525 1375);
FORCEADD OFFPAGE..1
(1225 175);
FORCEPROP 2 LAST $XR0 143 
J 0
(943 175);
DISPLAY 0.638298 (943 175);
PAINT MONO (943 175);
FORCEPROP 2 LAST CDS_LIB standard
J 2
(1225 175);
DISPLAY INVISIBLE (1225 175);
FORCEPROP 1 LAST OFFPAGE TRUE
J 0
(1550 50);
DISPLAY 0.872340 (1550 50);
PAINT GREEN (1550 50);
DISPLAY INVISIBLE (1550 50);
FORCEPROP 1 LAST COMMENT_BODY TRUE
J 0
(1350 75);
DISPLAY 0.872340 (1350 75);
PAINT GREEN (1350 75);
DISPLAY INVISIBLE (1350 75);
FORCEPROP 2 LAST PATH I51
J 2
(1050 250);
DISPLAY 1.021277 (1050 250);
DISPLAY INVISIBLE (1050 250);
FORCEADD Q_RES..1
(800 -675);
FORCEPROP 1 LAST LOCATION R3307
J 0
(625 -675);
DISPLAY 0.510638 (625 -675);
FORCEPROP 0 LAST $SEC 1
J 0
(750 -600);
DISPLAY 0.680851 (750 -600);
PAINT MONO (750 -600);
DISPLAY INVISIBLE (750 -600);
FORCEPROP 0 LAST CDS_SEC 1
J 0
(750 -600);
DISPLAY 1.021277 (750 -600);
DISPLAY INVISIBLE (750 -600);
FORCEPROP 1 LASTPIN (700 -675) $PN 1
J 0
(712 -663);
DISPLAY 0.787234 (712 -663);
PAINT MONO (712 -663);
FORCEPROP 1 LASTPIN (900 -675) $PN 2
J 0
(862 -663);
DISPLAY 0.787234 (862 -663);
PAINT MONO (862 -663);
FORCEPROP 1 LAST WATTAGE 1/16W
J 2
(950 -725);
DISPLAY 0.404255 (950 -725);
FORCEPROP 1 LAST VALUE 0
J 2
(950 -675);
DISPLAY 0.510638 (950 -675);
FORCEPROP 1 LAST MATERIAL CHIP
J 0
(750 -775);
DISPLAY 0.404255 (750 -775);
FORCEPROP 1 LAST TOLERANCE 5%
J 0
(975 -675);
DISPLAY 0.510638 (975 -675);
FORCEPROP 1 LAST PACK_TYPE 0402LF
J 0
(750 -725);
DISPLAY 0.404255 (750 -725);
FORCEPROP 2 LAST CDS_LIB pure_quanta
J 0
(800 -675);
DISPLAY INVISIBLE (800 -675);
FORCEPROP 1 LAST PATH I52
J 0
(750 -525);
DISPLAY 0.978723 (750 -525);
PAINT WHITE (750 -525);
DISPLAY INVISIBLE (750 -525);
FORCEPROP 1 LAST PART_NUMBER CS00002JB13
J 0
(750 -750);
DISPLAY 0.404255 (750 -750);
DISPLAY INVISIBLE (750 -750);
FORCEADD OFFPAGE..2
R 2
(-200 -675);
FORCEPROP 2 LAST $XR0 143 
J 0
(-455 -675);
DISPLAY 0.638298 (-455 -675);
PAINT MONO (-455 -675);
FORCEPROP 2 LAST CDS_LIB standard
J 2
(-200 -675);
DISPLAY INVISIBLE (-200 -675);
FORCEPROP 1 LAST OFFPAGE TRUE
J 2
(-525 -800);
DISPLAY 0.872340 (-525 -800);
PAINT GREEN (-525 -800);
DISPLAY INVISIBLE (-525 -800);
FORCEPROP 1 LAST COMMENT_BODY TRUE
J 2
(-155 -770);
DISPLAY 0.872340 (-155 -770);
PAINT GREEN (-155 -770);
DISPLAY INVISIBLE (-155 -770);
FORCEPROP 2 LAST PATH I53
J 0
(-150 -600);
DISPLAY 1.021277 (-150 -600);
DISPLAY INVISIBLE (-150 -600);
FORCEADD OFFPAGE..1
(700 2300);
FORCEPROP 2 LAST $XR0 143 
J 0
(448 2300);
DISPLAY 0.638298 (448 2300);
PAINT MONO (448 2300);
FORCEPROP 2 LAST CDS_LIB standard
J 0
(700 2300);
DISPLAY INVISIBLE (700 2300);
FORCEPROP 1 LAST OFFPAGE TRUE
J 0
(1025 2175);
DISPLAY 0.872340 (1025 2175);
PAINT GREEN (1025 2175);
DISPLAY INVISIBLE (1025 2175);
FORCEPROP 1 LAST COMMENT_BODY TRUE
J 0
(825 2200);
DISPLAY 0.872340 (825 2200);
PAINT GREEN (825 2200);
DISPLAY INVISIBLE (825 2200);
FORCEPROP 2 LAST PATH I54
J 0
(750 2375);
DISPLAY 1.021277 (750 2375);
DISPLAY INVISIBLE (750 2375);
FORCEADD OFFPAGE..2
(3100 2300);
FORCEPROP 2 LAST $XR0 132 
J 0
(3289 2300);
DISPLAY 0.638298 (3289 2300);
PAINT MONO (3289 2300);
FORCEPROP 2 LAST CDS_LIB standard
J 2
(3100 2300);
DISPLAY INVISIBLE (3100 2300);
FORCEPROP 1 LAST OFFPAGE TRUE
J 0
(3425 2175);
DISPLAY 0.872340 (3425 2175);
PAINT GREEN (3425 2175);
DISPLAY INVISIBLE (3425 2175);
FORCEPROP 1 LAST COMMENT_BODY TRUE
J 0
(3055 2205);
DISPLAY 0.872340 (3055 2205);
PAINT GREEN (3055 2205);
DISPLAY INVISIBLE (3055 2205);
FORCEPROP 2 LAST PATH I56
J 2
(3050 2375);
DISPLAY 1.021277 (3050 2375);
DISPLAY INVISIBLE (3050 2375);
FORCEADD OFFPAGE..2
(3350 175);
FORCEPROP 2 LAST $XR0 138 
J 0
(3539 175);
DISPLAY 0.638298 (3539 175);
PAINT MONO (3539 175);
FORCEPROP 2 LAST CDS_LIB standard
J 0
(3350 175);
DISPLAY INVISIBLE (3350 175);
FORCEPROP 1 LAST OFFPAGE TRUE
J 0
(3675 50);
DISPLAY 0.872340 (3675 50);
PAINT GREEN (3675 50);
DISPLAY INVISIBLE (3675 50);
FORCEPROP 1 LAST COMMENT_BODY TRUE
J 0
(3305 80);
DISPLAY 0.872340 (3305 80);
PAINT GREEN (3305 80);
DISPLAY INVISIBLE (3305 80);
FORCEPROP 2 LAST PATH I58
J 0
(3525 250);
DISPLAY 1.021277 (3525 250);
DISPLAY INVISIBLE (3525 250);
FORCEADD OFFPAGE..1
R 2
(3375 -675);
FORCEPROP 2 LAST $XR0 138 
J 0
(3561 -675);
DISPLAY 0.638298 (3561 -675);
PAINT MONO (3561 -675);
FORCEPROP 2 LAST CDS_LIB standard
J 0
(3375 -675);
DISPLAY INVISIBLE (3375 -675);
FORCEPROP 1 LAST OFFPAGE TRUE
J 2
(3050 -800);
DISPLAY 0.872340 (3050 -800);
PAINT GREEN (3050 -800);
DISPLAY INVISIBLE (3050 -800);
FORCEPROP 1 LAST COMMENT_BODY TRUE
J 2
(3250 -775);
DISPLAY 0.872340 (3250 -775);
PAINT GREEN (3250 -775);
DISPLAY INVISIBLE (3250 -775);
FORCEPROP 2 LAST PATH I59
J 0
(3550 -600);
DISPLAY 1.021277 (3550 -600);
DISPLAY INVISIBLE (3550 -600);
FORCEADD OFFPAGE..1
(-3600 -100);
FORCEPROP 2 LAST $XR1 140 
J 0
(-4002 -100);
DISPLAY 0.638298 (-4002 -100);
PAINT MONO (-4002 -100);
FORCEPROP 2 LAST $XR0 137 
J 0
(-3882 -100);
DISPLAY 0.638298 (-3882 -100);
PAINT MONO (-3882 -100);
FORCEPROP 2 LAST CDS_LIB standard
J 0
(-3600 -100);
PAINT MONO (-3600 -100);
DISPLAY INVISIBLE (-3600 -100);
FORCEPROP 1 LAST OFFPAGE TRUE
J 0
(-3275 -225);
DISPLAY 0.872340 (-3275 -225);
PAINT GREEN (-3275 -225);
DISPLAY INVISIBLE (-3275 -225);
FORCEPROP 1 LAST COMMENT_BODY TRUE
J 0
(-3475 -200);
DISPLAY 0.872340 (-3475 -200);
PAINT GREEN (-3475 -200);
DISPLAY INVISIBLE (-3475 -200);
FORCEPROP 2 LAST PATH I6
J 0
(-3875 -50);
DISPLAY 1.021277 (-3875 -50);
DISPLAY INVISIBLE (-3875 -50);
FORCEADD UNIVERSAL_GND..1
(2375 2175);
FORCEPROP 3 LASTPIN (2375 2225) SIG_NAME GND\g
J 0
(2385 2235);
DISPLAY 0.659574 (2385 2235);
PAINT MONO (2385 2235);
DISPLAY INVISIBLE (2385 2235);
FORCEPROP 2 LAST CDS_LIB pure_quanta_power
J 0
(2375 2175);
DISPLAY INVISIBLE (2375 2175);
FORCEPROP 1 LAST HDL_POWER GND
J 1
(2400 2100);
DISPLAY 0.872340 (2400 2100);
PAINT GREEN (2400 2100);
DISPLAY INVISIBLE (2400 2100);
FORCEPROP 1 LAST PATH I60
J 0
(2450 2175);
DISPLAY 0.872340 (2450 2175);
PAINT AQUA (2450 2175);
DISPLAY INVISIBLE (2450 2175);
FORCEADD UNIVERSAL_GND..1
(2375 1325);
FORCEPROP 3 LASTPIN (2375 1375) SIG_NAME GND\g
J 0
(2385 1385);
DISPLAY 0.659574 (2385 1385);
PAINT MONO (2385 1385);
DISPLAY INVISIBLE (2385 1385);
FORCEPROP 2 LAST CDS_LIB pure_quanta_power
J 0
(2375 1325);
DISPLAY INVISIBLE (2375 1325);
FORCEPROP 1 LAST HDL_POWER GND
J 1
(2400 1250);
DISPLAY 0.872340 (2400 1250);
PAINT GREEN (2400 1250);
DISPLAY INVISIBLE (2400 1250);
FORCEPROP 1 LAST PATH I61
J 0
(2450 1325);
DISPLAY 0.872340 (2450 1325);
PAINT AQUA (2450 1325);
DISPLAY INVISIBLE (2450 1325);
FORCEADD UNIVERSAL_GND..1
(2550 50);
FORCEPROP 3 LASTPIN (2550 100) SIG_NAME GND\g
J 0
(2560 110);
DISPLAY 0.659574 (2560 110);
PAINT MONO (2560 110);
DISPLAY INVISIBLE (2560 110);
FORCEPROP 2 LAST CDS_LIB pure_quanta_power
J 0
(2550 50);
DISPLAY INVISIBLE (2550 50);
FORCEPROP 1 LAST HDL_POWER GND
J 1
(2575 -25);
DISPLAY 0.872340 (2575 -25);
PAINT GREEN (2575 -25);
DISPLAY INVISIBLE (2575 -25);
FORCEPROP 1 LAST PATH I62
J 0
(2625 50);
DISPLAY 0.872340 (2625 50);
PAINT AQUA (2625 50);
DISPLAY INVISIBLE (2625 50);
FORCEADD UNIVERSAL_GND..1
(2525 -800);
FORCEPROP 3 LASTPIN (2525 -750) SIG_NAME GND\g
J 0
(2535 -740);
DISPLAY 0.659574 (2535 -740);
PAINT MONO (2535 -740);
DISPLAY INVISIBLE (2535 -740);
FORCEPROP 2 LAST CDS_LIB pure_quanta_power
J 0
(2525 -800);
DISPLAY INVISIBLE (2525 -800);
FORCEPROP 1 LAST HDL_POWER GND
J 1
(2550 -875);
DISPLAY 0.872340 (2550 -875);
PAINT GREEN (2550 -875);
DISPLAY INVISIBLE (2550 -875);
FORCEPROP 1 LAST PATH I63
J 0
(2600 -800);
DISPLAY 0.872340 (2600 -800);
PAINT AQUA (2600 -800);
DISPLAY INVISIBLE (2600 -800);
FORCEADD Q_RES..1
(-1450 2850);
FORCEPROP 1 LAST LOCATION R8013
J 0
(-1700 2850);
DISPLAY 0.787234 (-1700 2850);
FORCEPROP 2 LAST SEC 1
J 0
(-1500 3050);
DISPLAY 0.680851 (-1500 3050);
PAINT MONO (-1500 3050);
DISPLAY INVISIBLE (-1500 3050);
FORCEPROP 1 LASTPIN (-1550 2850) $PN 1
J 0
(-1538 2862);
DISPLAY 0.638298 (-1538 2862);
PAINT MONO (-1538 2862);
FORCEPROP 1 LASTPIN (-1350 2850) $PN 2
J 0
(-1388 2862);
DISPLAY 0.638298 (-1388 2862);
PAINT MONO (-1388 2862);
FORCEPROP 1 LAST TOLERANCE 5%
J 0
(-1375 2800);
DISPLAY 0.787234 (-1375 2800);
FORCEPROP 1 LAST WATTAGE 1/16W
J 2
(-1425 2925);
DISPLAY 0.787234 (-1425 2925);
FORCEPROP 1 LAST MATERIAL EMPTY
J 0
(-1500 2975);
DISPLAY 0.787234 (-1500 2975);
FORCEPROP 1 LAST PACK_TYPE 0402LF
J 0
(-1375 2925);
DISPLAY 0.787234 (-1375 2925);
FORCEPROP 1 LAST VALUE 0
J 2
(-1525 2800);
DISPLAY 0.787234 (-1525 2800);
FORCEPROP 2 LAST SEC_TYPE 0402LF
J 0
(-1500 3050);
DISPLAY 0.680851 (-1500 3050);
DISPLAY INVISIBLE (-1500 3050);
FORCEPROP 2 LAST CDS_LIB pure_quanta
J 0
(-1450 2850);
DISPLAY INVISIBLE (-1450 2850);
FORCEPROP 1 LAST PATH I64
J 0
(-1500 3000);
DISPLAY 0.978723 (-1500 3000);
PAINT WHITE (-1500 3000);
DISPLAY INVISIBLE (-1500 3000);
FORCEPROP 1 LAST PART_NUMBER CS00002JB13
J 0
(-1500 2950);
DISPLAY 0.978723 (-1500 2950);
DISPLAY INVISIBLE (-1500 2950);
FORCEADD Q_RES..1
(-1475 1950);
FORCEPROP 1 LAST LOCATION R8014
J 0
(-1725 1950);
DISPLAY 0.787234 (-1725 1950);
FORCEPROP 2 LAST SEC 1
J 0
(-1525 2150);
DISPLAY 0.680851 (-1525 2150);
PAINT MONO (-1525 2150);
DISPLAY INVISIBLE (-1525 2150);
FORCEPROP 1 LASTPIN (-1575 1950) $PN 1
J 0
(-1560 1985);
DISPLAY 0.638298 (-1560 1985);
PAINT MONO (-1560 1985);
FORCEPROP 1 LASTPIN (-1375 1950) $PN 2
J 0
(-1435 1985);
DISPLAY 0.638298 (-1435 1985);
PAINT MONO (-1435 1985);
FORCEPROP 1 LAST MATERIAL EMPTY
J 0
(-1525 2075);
DISPLAY 0.787234 (-1525 2075);
FORCEPROP 1 LAST TOLERANCE 5%
J 0
(-1400 1900);
DISPLAY 0.787234 (-1400 1900);
FORCEPROP 1 LAST WATTAGE 1/16W
J 2
(-1450 2025);
DISPLAY 0.787234 (-1450 2025);
FORCEPROP 1 LAST VALUE 0
J 2
(-1550 1900);
DISPLAY 0.787234 (-1550 1900);
FORCEPROP 1 LAST PACK_TYPE 0402LF
J 0
(-1400 2025);
DISPLAY 0.787234 (-1400 2025);
FORCEPROP 2 LAST CDS_LIB pure_quanta
J 0
(-1475 1950);
DISPLAY INVISIBLE (-1475 1950);
FORCEPROP 2 LAST SEC_TYPE 0402LF
J 0
(-1525 2150);
DISPLAY 0.680851 (-1525 2150);
DISPLAY INVISIBLE (-1525 2150);
FORCEPROP 1 LAST PATH I65
J 0
(-1525 2100);
DISPLAY 0.978723 (-1525 2100);
PAINT WHITE (-1525 2100);
DISPLAY INVISIBLE (-1525 2100);
FORCEPROP 1 LAST PART_NUMBER CS00002JB13
J 0
(-1525 2050);
DISPLAY 0.978723 (-1525 2050);
DISPLAY INVISIBLE (-1525 2050);
FORCEADD Q_RES..1
(-1450 750);
FORCEPROP 1 LAST LOCATION R8015
J 0
(-1700 750);
DISPLAY 0.787234 (-1700 750);
FORCEPROP 2 LAST SEC 1
J 0
(-1500 950);
DISPLAY 0.680851 (-1500 950);
PAINT MONO (-1500 950);
DISPLAY INVISIBLE (-1500 950);
FORCEPROP 1 LASTPIN (-1550 750) $PN 1
J 0
(-1538 762);
DISPLAY 0.787234 (-1538 762);
PAINT MONO (-1538 762);
FORCEPROP 1 LASTPIN (-1350 750) $PN 2
J 0
(-1388 762);
DISPLAY 0.787234 (-1388 762);
PAINT MONO (-1388 762);
FORCEPROP 1 LAST VALUE 0
J 2
(-1525 700);
DISPLAY 0.787234 (-1525 700);
FORCEPROP 1 LAST WATTAGE 1/16W
J 2
(-1425 825);
DISPLAY 0.787234 (-1425 825);
FORCEPROP 1 LAST MATERIAL EMPTY
J 0
(-1500 875);
DISPLAY 0.787234 (-1500 875);
FORCEPROP 1 LAST PACK_TYPE 0402LF
J 0
(-1375 825);
DISPLAY 0.787234 (-1375 825);
FORCEPROP 1 LAST TOLERANCE 5%
J 0
(-1400 700);
DISPLAY 0.787234 (-1400 700);
FORCEPROP 2 LAST CDS_LIB pure_quanta
J 0
(-1450 750);
DISPLAY INVISIBLE (-1450 750);
FORCEPROP 2 LAST SEC_TYPE 0402LF
J 0
(-1500 950);
DISPLAY 0.680851 (-1500 950);
DISPLAY INVISIBLE (-1500 950);
FORCEPROP 1 LAST PATH I66
J 0
(-1500 900);
DISPLAY 0.978723 (-1500 900);
PAINT WHITE (-1500 900);
DISPLAY INVISIBLE (-1500 900);
FORCEPROP 1 LAST PART_NUMBER CS00002JB13
J 0
(-1500 850);
DISPLAY 0.978723 (-1500 850);
DISPLAY INVISIBLE (-1500 850);
FORCEADD Q_RES..1
(-1475 -150);
FORCEPROP 1 LAST LOCATION R8016
J 0
(-1700 -150);
DISPLAY 0.787234 (-1700 -150);
FORCEPROP 2 LAST SEC 1
J 0
(-1525 50);
DISPLAY 0.680851 (-1525 50);
PAINT MONO (-1525 50);
DISPLAY INVISIBLE (-1525 50);
FORCEPROP 1 LASTPIN (-1575 -150) $PN 1
J 0
(-1563 -138);
DISPLAY 0.787234 (-1563 -138);
PAINT MONO (-1563 -138);
FORCEPROP 1 LASTPIN (-1375 -150) $PN 2
J 0
(-1413 -138);
DISPLAY 0.787234 (-1413 -138);
PAINT MONO (-1413 -138);
FORCEPROP 1 LAST MATERIAL EMPTY
J 0
(-1525 -25);
DISPLAY 0.787234 (-1525 -25);
FORCEPROP 1 LAST VALUE 0
J 2
(-1575 -200);
DISPLAY 0.787234 (-1575 -200);
FORCEPROP 1 LAST TOLERANCE 5%
J 0
(-1375 -200);
DISPLAY 0.787234 (-1375 -200);
FORCEPROP 1 LAST PACK_TYPE 0402LF
J 0
(-1400 -75);
DISPLAY 0.787234 (-1400 -75);
FORCEPROP 1 LAST WATTAGE 1/16W
J 2
(-1450 -75);
DISPLAY 0.787234 (-1450 -75);
FORCEPROP 2 LAST CDS_LIB pure_quanta
J 0
(-1475 -150);
DISPLAY INVISIBLE (-1475 -150);
FORCEPROP 2 LAST SEC_TYPE 0402LF
J 0
(-1525 50);
DISPLAY 0.680851 (-1525 50);
DISPLAY INVISIBLE (-1525 50);
FORCEPROP 1 LAST PATH I67
J 0
(-1525 0);
DISPLAY 0.978723 (-1525 0);
PAINT WHITE (-1525 0);
DISPLAY INVISIBLE (-1525 0);
FORCEPROP 1 LAST PART_NUMBER CS00002JB13
J 0
(-1525 -50);
DISPLAY 0.978723 (-1525 -50);
DISPLAY INVISIBLE (-1525 -50);
FORCEADD Q_CAP..1
R 2
(-1200 2575);
FORCEPROP 1 LAST LOCATION C8001
J 2
(-1250 2675);
DISPLAY 0.808511 (-1250 2675);
FORCEPROP 2 LAST SEC 1
J 0
(-1250 2775);
DISPLAY 0.680851 (-1250 2775);
PAINT MONO (-1250 2775);
DISPLAY INVISIBLE (-1250 2775);
FORCEPROP 1 LASTPIN (-1200 2675) $PN 1
J 2
(-1210 2655);
DISPLAY 0.787234 (-1210 2655);
PAINT MONO (-1210 2655);
FORCEPROP 1 LASTPIN (-1200 2475) $PN 2
J 2
(-1210 2455);
DISPLAY 0.787234 (-1210 2455);
PAINT MONO (-1210 2455);
FORCEPROP 1 LAST MATERIAL EMPTY
J 2
(-1250 2475);
DISPLAY 0.638298 (-1250 2475);
FORCEPROP 1 LAST TOLERANCE 10%
J 2
(-1250 2525);
DISPLAY 0.638298 (-1250 2525);
FORCEPROP 1 LAST VALUE 0.1UF
J 2
(-1250 2625);
DISPLAY 0.638298 (-1250 2625);
FORCEPROP 1 LAST VOLTAGE 25V
J 2
(-1250 2575);
DISPLAY 0.638298 (-1250 2575);
FORCEPROP 1 LAST PACK_TYPE 0402
J 2
(-1250 2375);
DISPLAY 0.638298 (-1250 2375);
FORCEPROP 2 LAST CDS_LIB pure_quanta
J 2
(-1200 2575);
DISPLAY INVISIBLE (-1200 2575);
FORCEPROP 2 LAST SEC_TYPE 0402
J 0
(-1250 2775);
DISPLAY 0.680851 (-1250 2775);
DISPLAY INVISIBLE (-1250 2775);
FORCEPROP 1 LAST PATH I68
J 2
(-1250 2725);
DISPLAY 0.978723 (-1250 2725);
PAINT WHITE (-1250 2725);
DISPLAY INVISIBLE (-1250 2725);
FORCEPROP 1 LAST PART_NUMBER CH4104K1B00
J 2
(-1250 2425);
DISPLAY 0.638298 (-1250 2425);
DISPLAY INVISIBLE (-1250 2425);
FORCEADD UNIVERSAL_GND..1
(-1200 2300);
FORCEPROP 3 LASTPIN (-1200 2350) SIG_NAME GND\g
J 0
(-1190 2360);
DISPLAY 0.659574 (-1190 2360);
PAINT MONO (-1190 2360);
DISPLAY INVISIBLE (-1190 2360);
FORCEPROP 2 LAST CDS_LIB pure_quanta_power
J 0
(-1200 2300);
DISPLAY INVISIBLE (-1200 2300);
FORCEPROP 1 LAST HDL_POWER GND
J 1
(-1175 2225);
DISPLAY 0.872340 (-1175 2225);
PAINT GREEN (-1175 2225);
DISPLAY INVISIBLE (-1175 2225);
FORCEPROP 1 LAST PATH I69
J 0
(-1125 2300);
DISPLAY 0.872340 (-1125 2300);
PAINT AQUA (-1125 2300);
DISPLAY INVISIBLE (-1125 2300);
FORCEADD OFFPAGE..1
(-3625 2900);
FORCEPROP 2 LAST $XR1 134 
J 0
(-4027 2900);
DISPLAY 0.638298 (-4027 2900);
PAINT MONO (-4027 2900);
FORCEPROP 2 LAST $XR0 131 
J 0
(-3907 2900);
DISPLAY 0.638298 (-3907 2900);
PAINT MONO (-3907 2900);
FORCEPROP 2 LAST CDS_LIB standard
J 0
(-3625 2900);
PAINT MONO (-3625 2900);
DISPLAY INVISIBLE (-3625 2900);
FORCEPROP 1 LAST OFFPAGE TRUE
J 0
(-3300 2775);
DISPLAY 0.872340 (-3300 2775);
PAINT GREEN (-3300 2775);
DISPLAY INVISIBLE (-3300 2775);
FORCEPROP 1 LAST COMMENT_BODY TRUE
J 0
(-3500 2800);
DISPLAY 0.872340 (-3500 2800);
PAINT GREEN (-3500 2800);
DISPLAY INVISIBLE (-3500 2800);
FORCEPROP 2 LAST PATH I7
J 0
(-3875 2950);
DISPLAY 1.021277 (-3875 2950);
DISPLAY INVISIBLE (-3875 2950);
FORCEADD Q_CAP..1
R 2
(-1200 1675);
FORCEPROP 1 LAST LOCATION C8002
J 2
(-1250 1775);
DISPLAY 0.787234 (-1250 1775);
FORCEPROP 0 LAST $SEC 1
J 0
(-1250 1825);
DISPLAY 0.680851 (-1250 1825);
PAINT MONO (-1250 1825);
DISPLAY INVISIBLE (-1250 1825);
FORCEPROP 0 LAST CDS_SEC 1
J 0
(-1250 1825);
DISPLAY 0.680851 (-1250 1825);
DISPLAY INVISIBLE (-1250 1825);
FORCEPROP 1 LASTPIN (-1200 1775) $PN 1
J 2
(-1210 1755);
DISPLAY 0.787234 (-1210 1755);
PAINT MONO (-1210 1755);
FORCEPROP 1 LASTPIN (-1200 1575) $PN 2
J 2
(-1210 1555);
DISPLAY 0.787234 (-1210 1555);
PAINT MONO (-1210 1555);
FORCEPROP 1 LAST VALUE 0.1UF
J 2
(-1250 1725);
DISPLAY 0.638298 (-1250 1725);
FORCEPROP 1 LAST VOLTAGE 25V
J 2
(-1250 1675);
DISPLAY 0.638298 (-1250 1675);
FORCEPROP 1 LAST TOLERANCE 10%
J 2
(-1250 1625);
DISPLAY 0.638298 (-1250 1625);
FORCEPROP 1 LAST MATERIAL EMPTY
J 2
(-1250 1575);
DISPLAY 0.638298 (-1250 1575);
FORCEPROP 1 LAST PACK_TYPE 0402
J 2
(-1250 1475);
DISPLAY 0.638298 (-1250 1475);
FORCEPROP 2 LAST CDS_LIB pure_quanta
J 0
(-1200 1675);
DISPLAY INVISIBLE (-1200 1675);
FORCEPROP 1 LAST PATH I70
J 2
(-1250 1825);
DISPLAY 0.978723 (-1250 1825);
PAINT WHITE (-1250 1825);
DISPLAY INVISIBLE (-1250 1825);
FORCEPROP 1 LAST PART_NUMBER CH4104K1B00
J 2
(-1250 1525);
DISPLAY 0.638298 (-1250 1525);
DISPLAY INVISIBLE (-1250 1525);
FORCEADD UNIVERSAL_GND..1
(-1200 1325);
FORCEPROP 3 LASTPIN (-1200 1375) SIG_NAME GND\g
J 0
(-1190 1385);
DISPLAY 0.659574 (-1190 1385);
PAINT MONO (-1190 1385);
DISPLAY INVISIBLE (-1190 1385);
FORCEPROP 2 LAST CDS_LIB pure_quanta_power
J 0
(-1200 1325);
DISPLAY INVISIBLE (-1200 1325);
FORCEPROP 1 LAST HDL_POWER GND
J 1
(-1175 1250);
DISPLAY 0.872340 (-1175 1250);
PAINT GREEN (-1175 1250);
DISPLAY INVISIBLE (-1175 1250);
FORCEPROP 1 LAST PATH I71
J 0
(-1125 1325);
DISPLAY 0.872340 (-1125 1325);
PAINT AQUA (-1125 1325);
DISPLAY INVISIBLE (-1125 1325);
FORCEADD Q_CAP..1
R 2
(-1175 475);
FORCEPROP 1 LAST LOCATION C8003
J 2
(-1225 575);
DISPLAY 0.978723 (-1225 575);
FORCEPROP 0 LAST $SEC 1
J 0
(-1225 625);
DISPLAY 0.680851 (-1225 625);
PAINT MONO (-1225 625);
DISPLAY INVISIBLE (-1225 625);
FORCEPROP 0 LAST CDS_SEC 1
J 0
(-1225 625);
DISPLAY 0.680851 (-1225 625);
DISPLAY INVISIBLE (-1225 625);
FORCEPROP 1 LASTPIN (-1175 575) $PN 1
J 2
(-1185 555);
DISPLAY 0.787234 (-1185 555);
PAINT MONO (-1185 555);
FORCEPROP 1 LASTPIN (-1175 375) $PN 2
J 2
(-1185 355);
DISPLAY 0.787234 (-1185 355);
PAINT MONO (-1185 355);
FORCEPROP 1 LAST MATERIAL EMPTY
J 2
(-1225 375);
DISPLAY 0.638298 (-1225 375);
FORCEPROP 1 LAST TOLERANCE 10%
J 2
(-1225 425);
DISPLAY 0.638298 (-1225 425);
FORCEPROP 1 LAST PACK_TYPE 0402
J 2
(-1225 275);
DISPLAY 0.638298 (-1225 275);
FORCEPROP 1 LAST VOLTAGE 25V
J 2
(-1225 475);
DISPLAY 0.638298 (-1225 475);
FORCEPROP 1 LAST VALUE 0.1UF
J 2
(-1225 525);
DISPLAY 0.638298 (-1225 525);
FORCEPROP 2 LAST CDS_LIB pure_quanta
J 0
(-1175 475);
DISPLAY INVISIBLE (-1175 475);
FORCEPROP 1 LAST PATH I72
J 2
(-1225 625);
DISPLAY 0.978723 (-1225 625);
PAINT WHITE (-1225 625);
DISPLAY INVISIBLE (-1225 625);
FORCEPROP 1 LAST PART_NUMBER CH4104K1B00
J 2
(-1225 325);
DISPLAY 0.638298 (-1225 325);
DISPLAY INVISIBLE (-1225 325);
FORCEADD UNIVERSAL_GND..1
(-1175 125);
FORCEPROP 3 LASTPIN (-1175 175) SIG_NAME GND\g
J 0
(-1165 185);
DISPLAY 0.659574 (-1165 185);
PAINT MONO (-1165 185);
DISPLAY INVISIBLE (-1165 185);
FORCEPROP 2 LAST CDS_LIB pure_quanta_power
J 0
(-1175 125);
DISPLAY INVISIBLE (-1175 125);
FORCEPROP 1 LAST HDL_POWER GND
J 1
(-1150 50);
DISPLAY 0.872340 (-1150 50);
PAINT GREEN (-1150 50);
DISPLAY INVISIBLE (-1150 50);
FORCEPROP 1 LAST PATH I73
J 0
(-1100 125);
DISPLAY 0.872340 (-1100 125);
PAINT AQUA (-1100 125);
DISPLAY INVISIBLE (-1100 125);
FORCEADD Q_CAP..1
R 2
(-1175 -425);
FORCEPROP 1 LAST LOCATION C8004
J 2
(-1225 -325);
DISPLAY 0.978723 (-1225 -325);
FORCEPROP 0 LAST $SEC 1
J 0
(-1225 -275);
DISPLAY 0.680851 (-1225 -275);
PAINT MONO (-1225 -275);
DISPLAY INVISIBLE (-1225 -275);
FORCEPROP 0 LAST CDS_SEC 1
J 0
(-1225 -275);
DISPLAY 0.680851 (-1225 -275);
DISPLAY INVISIBLE (-1225 -275);
FORCEPROP 1 LASTPIN (-1175 -325) $PN 1
J 2
(-1185 -345);
DISPLAY 0.787234 (-1185 -345);
PAINT MONO (-1185 -345);
FORCEPROP 1 LASTPIN (-1175 -525) $PN 2
J 2
(-1185 -545);
DISPLAY 0.787234 (-1185 -545);
PAINT MONO (-1185 -545);
FORCEPROP 1 LAST PACK_TYPE 0402
J 2
(-1225 -625);
DISPLAY 0.638298 (-1225 -625);
FORCEPROP 1 LAST VALUE 0.1UF
J 2
(-1225 -375);
DISPLAY 0.638298 (-1225 -375);
FORCEPROP 1 LAST VOLTAGE 25V
J 2
(-1225 -425);
DISPLAY 0.638298 (-1225 -425);
FORCEPROP 1 LAST MATERIAL EMPTY
J 2
(-1225 -525);
DISPLAY 0.638298 (-1225 -525);
FORCEPROP 1 LAST TOLERANCE 10%
J 2
(-1225 -475);
DISPLAY 0.638298 (-1225 -475);
FORCEPROP 2 LAST CDS_LIB pure_quanta
J 0
(-1175 -425);
DISPLAY INVISIBLE (-1175 -425);
FORCEPROP 1 LAST PATH I74
J 2
(-1225 -275);
DISPLAY 0.978723 (-1225 -275);
PAINT WHITE (-1225 -275);
DISPLAY INVISIBLE (-1225 -275);
FORCEPROP 1 LAST PART_NUMBER CH4104K1B00
J 2
(-1225 -575);
DISPLAY 0.638298 (-1225 -575);
DISPLAY INVISIBLE (-1225 -575);
FORCEADD UNIVERSAL_GND..1
(-1175 -775);
FORCEPROP 3 LASTPIN (-1175 -725) SIG_NAME GND\g
J 0
(-1165 -715);
DISPLAY 0.659574 (-1165 -715);
PAINT MONO (-1165 -715);
DISPLAY INVISIBLE (-1165 -715);
FORCEPROP 2 LAST CDS_LIB pure_quanta_power
J 0
(-1175 -775);
DISPLAY INVISIBLE (-1175 -775);
FORCEPROP 1 LAST HDL_POWER GND
J 1
(-1150 -850);
DISPLAY 0.872340 (-1150 -850);
PAINT GREEN (-1150 -850);
DISPLAY INVISIBLE (-1150 -850);
FORCEPROP 1 LAST PATH I75
J 0
(-1100 -775);
DISPLAY 0.872340 (-1100 -775);
PAINT AQUA (-1100 -775);
DISPLAY INVISIBLE (-1100 -775);
FORCEADD OFFPAGE..1
(-3625 2000);
FORCEPROP 2 LAST $XR1 134 
J 0
(-4027 2000);
DISPLAY 0.638298 (-4027 2000);
PAINT MONO (-4027 2000);
FORCEPROP 2 LAST $XR0 131 
J 0
(-3907 2000);
DISPLAY 0.638298 (-3907 2000);
PAINT MONO (-3907 2000);
FORCEPROP 2 LAST CDS_LIB standard
J 0
(-3625 2000);
PAINT MONO (-3625 2000);
DISPLAY INVISIBLE (-3625 2000);
FORCEPROP 1 LAST OFFPAGE TRUE
J 0
(-3300 1875);
DISPLAY 0.872340 (-3300 1875);
PAINT GREEN (-3300 1875);
DISPLAY INVISIBLE (-3300 1875);
FORCEPROP 1 LAST COMMENT_BODY TRUE
J 0
(-3500 1900);
DISPLAY 0.872340 (-3500 1900);
PAINT GREEN (-3500 1900);
DISPLAY INVISIBLE (-3500 1900);
FORCEPROP 2 LAST PATH I8
J 0
(-3875 2050);
DISPLAY 1.021277 (-3875 2050);
DISPLAY INVISIBLE (-3875 2050);
FORCEADD OFFPAGE..1
(-3625 1900);
FORCEPROP 2 LAST $XR1 134 
J 0
(-4027 1900);
DISPLAY 0.638298 (-4027 1900);
PAINT MONO (-4027 1900);
FORCEPROP 2 LAST $XR0 131 
J 0
(-3907 1900);
DISPLAY 0.638298 (-3907 1900);
PAINT MONO (-3907 1900);
FORCEPROP 2 LAST CDS_LIB standard
J 0
(-3625 1900);
PAINT MONO (-3625 1900);
DISPLAY INVISIBLE (-3625 1900);
FORCEPROP 1 LAST OFFPAGE TRUE
J 0
(-3300 1775);
DISPLAY 0.872340 (-3300 1775);
PAINT GREEN (-3300 1775);
DISPLAY INVISIBLE (-3300 1775);
FORCEPROP 1 LAST COMMENT_BODY TRUE
J 0
(-3500 1800);
DISPLAY 0.872340 (-3500 1800);
PAINT GREEN (-3500 1800);
DISPLAY INVISIBLE (-3500 1800);
FORCEPROP 2 LAST PATH I9
J 0
(-3875 1950);
DISPLAY 1.021277 (-3875 1950);
DISPLAY INVISIBLE (-3875 1950);
FORCEADD DNS..2
(-2500 700);
PAINT RED (-2500 700);
FORCEPROP 2 LAST CDS_LIB mstr_misc
J 0
(-2500 700);
DISPLAY INVISIBLE (-2500 700);
FORCEPROP 1 LAST COMMENT_BODY TRUE
R 1
J 0
(-2425 475);
DISPLAY 0.872340 (-2425 475);
PAINT GREEN (-2425 475);
DISPLAY INVISIBLE (-2425 475);
FORCEADD DNS..2
(-1450 -100);
PAINT RED (-1450 -100);
FORCEPROP 2 LAST CDS_LIB mstr_misc
J 0
(-1450 -100);
DISPLAY INVISIBLE (-1450 -100);
FORCEPROP 1 LAST COMMENT_BODY TRUE
R 1
J 0
(-1375 -325);
DISPLAY 0.872340 (-1375 -325);
PAINT GREEN (-1375 -325);
DISPLAY INVISIBLE (-1375 -325);
FORCEADD DNS..2
(-1425 800);
PAINT RED (-1425 800);
FORCEPROP 2 LAST CDS_LIB mstr_misc
J 0
(-1425 800);
DISPLAY INVISIBLE (-1425 800);
FORCEPROP 1 LAST COMMENT_BODY TRUE
R 1
J 0
(-1350 575);
DISPLAY 0.872340 (-1350 575);
PAINT GREEN (-1350 575);
DISPLAY INVISIBLE (-1350 575);
FORCEADD DNS..2
(-1475 2025);
PAINT RED (-1475 2025);
FORCEPROP 2 LAST CDS_LIB mstr_misc
J 0
(-1475 2025);
DISPLAY INVISIBLE (-1475 2025);
FORCEPROP 1 LAST COMMENT_BODY TRUE
R 1
J 0
(-1400 1800);
DISPLAY 0.872340 (-1400 1800);
PAINT GREEN (-1400 1800);
DISPLAY INVISIBLE (-1400 1800);
FORCEADD DNS..2
(-1425 2925);
PAINT RED (-1425 2925);
FORCEPROP 2 LAST CDS_LIB mstr_misc
J 0
(-1425 2925);
DISPLAY INVISIBLE (-1425 2925);
FORCEPROP 1 LAST COMMENT_BODY TRUE
R 1
J 0
(-1350 2700);
DISPLAY 0.872340 (-1350 2700);
PAINT GREEN (-1350 2700);
DISPLAY INVISIBLE (-1350 2700);
FORCEADD DNS..2
(-500 375);
PAINT RED (-500 375);
FORCEPROP 2 LAST CDS_LIB mstr_misc
J 0
(-500 375);
DISPLAY INVISIBLE (-500 375);
FORCEPROP 1 LAST COMMENT_BODY TRUE
R 1
J 0
(-425 150);
DISPLAY 0.872340 (-425 150);
PAINT GREEN (-425 150);
DISPLAY INVISIBLE (-425 150);
FORCEADD DNS..2
(-450 2325);
PAINT RED (-450 2325);
FORCEPROP 2 LAST CDS_LIB mstr_misc
J 0
(-450 2325);
DISPLAY INVISIBLE (-450 2325);
FORCEPROP 1 LAST COMMENT_BODY TRUE
R 1
J 0
(-375 2100);
DISPLAY 0.872340 (-375 2100);
PAINT GREEN (-375 2100);
DISPLAY INVISIBLE (-375 2100);
FORCEADD DNS..2
(-2600 0);
PAINT RED (-2600 0);
FORCEPROP 2 LAST CDS_LIB mstr_misc
J 0
(-2600 0);
DISPLAY INVISIBLE (-2600 0);
FORCEPROP 1 LAST COMMENT_BODY TRUE
R 1
J 0
(-2525 -225);
DISPLAY 0.872340 (-2525 -225);
PAINT GREEN (-2525 -225);
DISPLAY INVISIBLE (-2525 -225);
FORCEADD DNS..2
(-2625 2075);
PAINT RED (-2625 2075);
FORCEPROP 2 LAST CDS_LIB mstr_misc
J 0
(-2625 2075);
DISPLAY INVISIBLE (-2625 2075);
FORCEPROP 1 LAST COMMENT_BODY TRUE
R 1
J 0
(-2550 1850);
DISPLAY 0.872340 (-2550 1850);
PAINT GREEN (-2550 1850);
DISPLAY INVISIBLE (-2550 1850);
FORCEADD DNS..2
(2000 1425);
PAINT RED (2000 1425);
FORCEPROP 2 LAST CDS_LIB mstr_misc
J 0
(2000 1425);
DISPLAY INVISIBLE (2000 1425);
FORCEPROP 1 LAST COMMENT_BODY TRUE
R 1
J 0
(2075 1200);
DISPLAY 0.872340 (2075 1200);
PAINT GREEN (2075 1200);
DISPLAY INVISIBLE (2075 1200);
FORCEADD DNS..2
(2025 2300);
PAINT RED (2025 2300);
FORCEPROP 2 LAST CDS_LIB mstr_misc
J 0
(2025 2300);
DISPLAY INVISIBLE (2025 2300);
FORCEPROP 1 LAST COMMENT_BODY TRUE
R 1
J 0
(2100 2075);
DISPLAY 0.872340 (2100 2075);
PAINT GREEN (2100 2075);
DISPLAY INVISIBLE (2100 2075);
FORCEADD DNS..2
(2200 200);
PAINT RED (2200 200);
FORCEPROP 2 LAST CDS_LIB mstr_misc
J 0
(2200 200);
DISPLAY INVISIBLE (2200 200);
FORCEPROP 1 LAST COMMENT_BODY TRUE
R 1
J 0
(2275 -25);
DISPLAY 0.872340 (2275 -25);
PAINT GREEN (2275 -25);
DISPLAY INVISIBLE (2275 -25);
FORCEADD DNS..2
(2200 -675);
PAINT RED (2200 -675);
FORCEPROP 2 LAST CDS_LIB mstr_misc
J 0
(2200 -675);
DISPLAY INVISIBLE (2200 -675);
FORCEPROP 1 LAST COMMENT_BODY TRUE
R 1
J 0
(2275 -900);
DISPLAY 0.872340 (2275 -900);
PAINT GREEN (2275 -900);
DISPLAY INVISIBLE (2275 -900);
FORCEADD DNS..2
(-1300 2575);
PAINT RED (-1300 2575);
FORCEPROP 2 LAST CDS_LIB mstr_misc
J 0
(-1300 2575);
DISPLAY INVISIBLE (-1300 2575);
FORCEPROP 1 LAST COMMENT_BODY TRUE
R 1
J 0
(-1225 2350);
DISPLAY 0.872340 (-1225 2350);
PAINT GREEN (-1225 2350);
DISPLAY INVISIBLE (-1225 2350);
FORCEADD DNS..2
(-1300 1675);
PAINT RED (-1300 1675);
FORCEPROP 2 LAST CDS_LIB mstr_misc
J 0
(-1300 1675);
DISPLAY INVISIBLE (-1300 1675);
FORCEPROP 1 LAST COMMENT_BODY TRUE
R 1
J 0
(-1225 1450);
DISPLAY 0.872340 (-1225 1450);
PAINT GREEN (-1225 1450);
DISPLAY INVISIBLE (-1225 1450);
FORCEADD DNS..2
(-1250 450);
PAINT RED (-1250 450);
FORCEPROP 2 LAST CDS_LIB mstr_misc
J 0
(-1250 450);
DISPLAY INVISIBLE (-1250 450);
FORCEPROP 1 LAST COMMENT_BODY TRUE
R 1
J 0
(-1175 225);
DISPLAY 0.872340 (-1175 225);
PAINT GREEN (-1175 225);
DISPLAY INVISIBLE (-1175 225);
FORCEADD DNS..2
(-2425 2750);
PAINT RED (-2425 2750);
FORCEPROP 2 LAST CDS_LIB mstr_misc
J 0
(-2425 2750);
DISPLAY INVISIBLE (-2425 2750);
FORCEPROP 1 LAST COMMENT_BODY TRUE
R 1
J 0
(-2350 2525);
DISPLAY 0.872340 (-2350 2525);
PAINT GREEN (-2350 2525);
DISPLAY INVISIBLE (-2350 2525);
FORCEADD DNS..2
(-1225 -425);
PAINT RED (-1225 -425);
FORCEPROP 2 LAST CDS_LIB mstr_misc
J 0
(-1225 -425);
DISPLAY INVISIBLE (-1225 -425);
FORCEPROP 1 LAST COMMENT_BODY TRUE
R 1
J 0
(-1150 -650);
DISPLAY 0.872340 (-1150 -650);
PAINT GREEN (-1150 -650);
DISPLAY INVISIBLE (-1150 -650);
FORCEADD QUANTA_TITLE_BLOCK_C..1
(5100 -2650);
FORCEPROP 0 LAST CDS_CON_LAST_MODIFIED Thu Sep 14 16:12:27 2023
J 0
(3215 -2635);
DISPLAY INVISIBLE (3215 -2635);
FORCEPROP 1 LAST CUSTOM_TXT_CDS <CON_LAST_MODIFIED>
J 0
(3215 -2635);
DISPLAY 0.978723 (3215 -2635);
FORCEPROP 2 LAST CUSTOM_TXT_CDS <XR_PAGE_TITLE>
J 0
(-2790 2600);
DISPLAY 0.638298 (-2790 2600);
PAINT PINK (-2790 2600);
DISPLAY INVISIBLE (-2790 2600);
FORCEPROP 1 LAST CUSTOM_TXT_CDS <NAME_2>
J 0
(1925 -2600);
FORCEPROP 1 LAST CUSTOM_TXT_CDS <NAME_1>
J 0
(1925 -2475);
FORCEPROP 1 LAST CUSTOM_TXT_CDS <Q_NUMBER>
J 0
(3697 -2547);
DISPLAY 1.212766 (3697 -2547);
FORCEPROP 1 LAST CUSTOM_TXT_CDS <Q_PROJ>
J 0
(2718 -2548);
DISPLAY 1.212766 (2718 -2548);
FORCEPROP 1 LAST CUSTOM_TXT_CDS <Q_REV>
J 0
(4916 -2547);
DISPLAY 1.212766 (4916 -2547);
FORCEPROP 1 LAST CUSTOM_TXT_CDS <CON_PAGE_NUM> OF <CON_TOTAL_PAGES>
J 0
(4654 -2632);
DISPLAY 0.978723 (4654 -2632);
FORCEPROP 1 LAST Q_TITLE OCP3.0 NCSI
J 0
(-4266 -2624);
DISPLAY 2.446809 (-4266 -2624);
PAINT GREEN (-4266 -2624);
FORCEPROP 2 LAST PAGE_BORDER TRUE
J 0
(-2790 2600);
DISPLAY 0.638298 (-2790 2600);
PAINT PINK (-2790 2600);
DISPLAY INVISIBLE (-2790 2600);
FORCEPROP 1 LAST CDS_LMAN_SYM_OUTLINE -9475,6775,100,-125
J 0
(5100 -2650);
DISPLAY 0.468085 (5100 -2650);
PAINT GREEN (5100 -2650);
DISPLAY INVISIBLE (5100 -2650);
FORCEPROP 2 LAST CDS_LIB pure_quanta
J 0
(5100 -2650);
DISPLAY INVISIBLE (5100 -2650);
FORCEPROP 2 LAST CDS_XR_PAGE_TITLE CR-143 : @T6G_MB_LIB.T6G(SCH_1):PAGE143
J 0
(-2790 2600);
DISPLAY 0.638298 (-2790 2600);
PAINT PINK (-2790 2600);
DISPLAY INVISIBLE (-2790 2600);
FORCEPROP 1 LAST Q_DEPT BU9
J 1
(1337 -2601);
DISPLAY 1.957447 (1337 -2601);
PAINT GREEN (1337 -2601);
DISPLAY INVISIBLE (1337 -2601);
FORCEPROP 1 LAST COMMENT_BODY TRUE
J 0
(5112 -2663);
DISPLAY 0.978723 (5112 -2663);
PAINT GREEN (5112 -2663);
DISPLAY INVISIBLE (5112 -2663);
WIRE 16 -1 (-2375 1075)(-2375 1000);
WIRE 16 -1 (-2475 3150)(-2475 3075);
WIRE 16 -1 (-2600 2700)(-2600 2625);
WIRE 16 -1 (-2600 600)(-2600 525);
WIRE 16 -1 (1525 475)(1525 400);
WIRE 16 -1 (1525 -350)(1525 -425);
WIRE 16 -1 (1325 2675)(1325 2600);
WIRE 16 -1 (1350 1825)(1350 1750);
WIRE 16 -1 (-325 2750)(-325 2675);
WIRE 16 -1 (-400 2250)(-400 2175);
WIRE 16 -1 (2325 2350)(2375 2350);
WIRE 16 -1 (2375 2350)(2375 2225);
WIRE 16 -1 (2325 1500)(2375 1500);
WIRE 16 -1 (2375 1500)(2375 1375);
WIRE 16 -1 (2500 225)(2550 225);
WIRE 16 -1 (2550 225)(2550 100);
WIRE 16 -1 (2475 -625)(2525 -625);
WIRE 16 -1 (2525 -625)(2525 -750);
WIRE 16 -1 (-1200 2475)(-1200 2350);
WIRE 16 -1 (-1200 1575)(-1200 1375);
WIRE 16 -1 (-1175 375)(-1175 175);
WIRE 16 -1 (-1175 -525)(-1175 -725);
WIRE 16 -1 (-3575 2800)(-2900 2800);
FORCEPROP 0 LAST CDS_PHYS_NET_NAME OCP_SFF_PRSNT1_R_N
J 0
(-2985 2842);
PAINT MONO (-2985 2842);
DISPLAY INVISIBLE (-2985 2842);
FORCEPROP 2 LAST SIG_NAME OCP_SFF_PRSNT1_R_N
J 0
(-3535 2810);
DISPLAY 0.553191 (-3535 2810);
PAINT WHITE (-3535 2810);
WIRE 16 -1 (-2475 3350)(-2475 3450);
WIRE 16 -1 (-2475 3525)(-2475 3450);
WIRE 16 -1 (-2475 3450)(-2600 3450);
WIRE 16 -1 (-2600 3000)(-2600 3450);
WIRE 16 -1 (-850 325)(-850 750);
WIRE 16 -1 (-850 325)(-700 325);
WIRE 16 -1 (-850 750)(-1175 750);
WIRE 16 -1 (-1175 750)(-1175 575);
WIRE 16 -1 (-1175 750)(-1350 750);
FORCEPROP 2 LAST SIG_NAME OCP_V3_2_PRSNT01_R1_N
J 0
(-1310 760);
DISPLAY 0.553191 (-1310 760);
FORCEPROP 2 LASTPROP $XRERR UNIQUE?
J 0
(-1550 760);
DISPLAY 0.638298 (-1550 760);
PAINT MONO (-1550 760);
DISPLAY INVISIBLE (-1550 760);
WIRE 16 -1 (-775 225)(-775 -150);
WIRE 16 -1 (-775 225)(-700 225);
WIRE 16 -1 (-775 -150)(-1175 -150);
WIRE 16 -1 (-1175 -150)(-1175 -325);
WIRE 16 -1 (-1175 -150)(-1375 -150);
FORCEPROP 2 LAST SIG_NAME OCP_V3_2_PRSNT23_R1_N
J 0
(-1335 -140);
DISPLAY 0.553191 (-1335 -140);
FORCEPROP 2 LASTPROP $XRERR UNIQUE?
J 0
(-1575 -140);
DISPLAY 0.638298 (-1575 -140);
PAINT MONO (-1575 -140);
DISPLAY INVISIBLE (-1575 -140);
WIRE 16 -1 (-850 2350)(-850 1950);
WIRE 16 -1 (-850 2350)(-700 2350);
WIRE 16 -1 (-850 1950)(-1200 1950);
WIRE 16 -1 (-1200 1950)(-1200 1775);
WIRE 16 -1 (-1200 1950)(-1375 1950);
FORCEPROP 2 LAST SIG_NAME OCP_SFF_PRSNT23_R1_N
J 0
(-1385 1960);
DISPLAY 0.553191 (-1385 1960);
FORCEPROP 2 LASTPROP $XRERR UNIQUE?
J 0
(-1625 1960);
DISPLAY 0.638298 (-1625 1960);
PAINT MONO (-1625 1960);
DISPLAY INVISIBLE (-1625 1960);
WIRE 16 -1 (-2300 2850)(-1550 2850);
FORCEPROP 0 LAST CDS_PHYS_NET_NAME OCP_SFF_PRSNT0_R_N
J 0
(-1635 2892);
PAINT MONO (-1635 2892);
DISPLAY INVISIBLE (-1635 2892);
FORCEPROP 2 LAST SIG_NAME OCP_SFF_PRSNT01_R_N
J 0
(-2235 2860);
DISPLAY 0.553191 (-2235 2860);
PAINT WHITE (-2235 2860);
FORCEPROP 2 LASTPROP $XRERR UNIQUE?
J 0
(-2475 2860);
DISPLAY 0.638298 (-2475 2860);
PAINT MONO (-2475 2860);
DISPLAY INVISIBLE (-2475 2860);
WIRE 16 -1 (1850 225)(1850 775);
WIRE 16 -1 (1900 225)(1850 225);
WIRE 16 -1 (1850 775)(1525 775);
WIRE 16 -1 (1525 675)(1525 775);
WIRE 16 -1 (1525 775)(1525 850);
WIRE 16 -1 (1850 -625)(1850 -50);
WIRE 16 -1 (1875 -625)(1850 -625);
WIRE 16 -1 (1850 -50)(1525 -50);
WIRE 16 -1 (1525 -150)(1525 -50);
WIRE 16 -1 (1525 -25)(1525 -50);
WIRE 16 -1 (1675 2350)(1675 2975);
WIRE 16 -1 (1725 2350)(1675 2350);
WIRE 16 -1 (1675 2975)(1325 2975);
WIRE 16 -1 (1325 2875)(1325 2975);
WIRE 16 -1 (1325 2975)(1325 3050);
WIRE 16 -1 (1675 1500)(1675 2100);
WIRE 16 -1 (1725 1500)(1675 1500);
WIRE 16 -1 (1675 2100)(1350 2100);
WIRE 16 -1 (1350 2025)(1350 2100);
WIRE 16 -1 (1350 2100)(1350 2125);
WIRE 16 -1 (-325 3125)(-325 3025);
WIRE 16 -1 (-325 3025)(-325 2950);
WIRE 16 -1 (-325 3025)(-400 3025);
WIRE 16 -1 (-400 2550)(-400 3025);
WIRE 16 -1 (-2375 1450)(-2375 1350);
WIRE 16 -1 (-2375 1350)(-2375 1275);
WIRE 16 -1 (-2375 1350)(-2600 1350);
WIRE 16 -1 (-2600 900)(-2600 1350);
WIRE 16 -1 (-1350 2850)(-1200 2850);
FORCEPROP 2 LAST SIG_NAME OCP_SFF_PRSNT01_R1_N
J 0
(-1310 2860);
DISPLAY 0.553191 (-1310 2860);
FORCEPROP 2 LASTPROP $XRERR UNIQUE?
J 0
(-1550 2860);
DISPLAY 0.638298 (-1550 2860);
PAINT MONO (-1550 2860);
DISPLAY INVISIBLE (-1550 2860);
WIRE 16 -1 (-850 2850)(-1200 2850);
WIRE 16 -1 (-1200 2850)(-1200 2675);
WIRE 16 -1 (-850 2850)(-850 2450);
WIRE 16 -1 (-850 2450)(-700 2450);
WIRE 16 -1 (-2300 1950)(-1575 1950);
FORCEPROP 0 LAST CDS_PHYS_NET_NAME OCP_SFF_PRSNT0_R_N
J 0
(-1660 1992);
PAINT MONO (-1660 1992);
DISPLAY INVISIBLE (-1660 1992);
FORCEPROP 2 LAST SIG_NAME OCP_SFF_PRSNT23_R_N
J 0
(-2260 1960);
DISPLAY 0.553191 (-2260 1960);
PAINT WHITE (-2260 1960);
FORCEPROP 2 LASTPROP $XRERR UNIQUE?
J 0
(-2500 1960);
DISPLAY 0.638298 (-2500 1960);
PAINT MONO (-2500 1960);
DISPLAY INVISIBLE (-2500 1960);
WIRE 16 -1 (-2300 750)(-1550 750);
FORCEPROP 0 LAST CDS_PHYS_NET_NAME OCP_SFF_PRSNT0_R_N
J 0
(-1635 792);
PAINT MONO (-1635 792);
DISPLAY INVISIBLE (-1635 792);
FORCEPROP 2 LAST SIG_NAME OCP_V3_2_PRSNT01_R_N
J 0
(-2260 760);
DISPLAY 0.553191 (-2260 760);
PAINT WHITE (-2260 760);
FORCEPROP 2 LASTPROP $XRERR UNIQUE?
J 0
(-2500 760);
DISPLAY 0.638298 (-2500 760);
PAINT MONO (-2500 760);
DISPLAY INVISIBLE (-2500 760);
WIRE 16 -1 (-2300 -150)(-1575 -150);
FORCEPROP 0 LAST CDS_PHYS_NET_NAME OCP_SFF_PRSNT0_R_N
J 0
(-1660 -108);
PAINT MONO (-1660 -108);
DISPLAY INVISIBLE (-1660 -108);
FORCEPROP 2 LAST SIG_NAME OCP_V3_2_PRSNT23_R_N
J 0
(-2260 -140);
DISPLAY 0.553191 (-2260 -140);
PAINT WHITE (-2260 -140);
FORCEPROP 2 LASTPROP $XRERR UNIQUE?
J 0
(-2500 -140);
DISPLAY 0.638298 (-2500 -140);
PAINT MONO (-2500 -140);
DISPLAY INVISIBLE (-2500 -140);
WIRE 16 -1 (175 2400)(725 2400);
FORCEPROP 0 LAST CDS_PHYS_NET_NAME OCP_SFF_PRSNT0_R_N
J 0
(215 2442);
PAINT MONO (215 2442);
DISPLAY INVISIBLE (215 2442);
WIRE 16 -1 (175 2400)(175 1550);
WIRE 16 -1 (-100 2400)(175 2400);
FORCEPROP 2 LAST SIG_NAME OCP_SFF_PRSNT_ALL_R_N
J 0
(40 2410);
DISPLAY 0.553191 (40 2410);
PAINT WHITE (40 2410);
FORCEPROP 2 LASTPROP $XRERR UNIQUE?
J 0
(-200 2410);
DISPLAY 0.638298 (-200 2410);
PAINT MONO (-200 2410);
DISPLAY INVISIBLE (-200 2410);
WIRE 16 -1 (175 1550)(525 1550);
WIRE 16 -1 (-100 275)(275 275);
FORCEPROP 2 LAST SIG_NAME OCP_V3_2_PRSNT_ALL_R_N
J 0
(-35 285);
DISPLAY 0.553191 (-35 285);
PAINT WHITE (-35 285);
FORCEPROP 2 LASTPROP $XRERR UNIQUE?
J 0
(-275 285);
DISPLAY 0.638298 (-275 285);
PAINT MONO (-275 285);
DISPLAY INVISIBLE (-275 285);
WIRE 16 -1 (275 275)(725 275);
FORCEPROP 0 LAST CDS_PHYS_NET_NAME OCP_SFF_PRSNT0_R_N
J 0
(1240 317);
PAINT MONO (1240 317);
DISPLAY INVISIBLE (1240 317);
WIRE 16 -1 (275 -575)(275 275);
WIRE 16 -1 (275 -575)(700 -575);
WIRE 16 -1 (-3550 700)(-2900 700);
FORCEPROP 0 LAST CDS_PHYS_NET_NAME OCP_V3_2_PRSNT1_R_N
J 0
(-3010 742);
PAINT MONO (-3010 742);
DISPLAY INVISIBLE (-3010 742);
FORCEPROP 2 LAST SIG_NAME OCP_V3_2_PRSNT1_R_N
J 0
(-3510 710);
DISPLAY 0.553191 (-3510 710);
PAINT WHITE (-3510 710);
WIRE 16 -1 (925 2400)(1725 2400);
FORCEPROP 2 LAST SIG_NAME OCP_SFF_PRSNT_ALL_R1_N
J 0
(1065 2410);
DISPLAY 0.510638 (1065 2410);
PAINT WHITE (1065 2410);
FORCEPROP 2 LASTPROP $XRERR UNIQUE?
J 0
(825 2410);
DISPLAY 0.638298 (825 2410);
PAINT MONO (825 2410);
DISPLAY INVISIBLE (825 2410);
WIRE 16 -1 (750 2300)(1725 2300);
FORCEPROP 2 LAST SIG_NAME OCP_SFF_RBT_ARB_IN_MUX2
J 0
(915 2310);
DISPLAY 0.553191 (915 2310);
PAINT WHITE (915 2310);
WIRE 16 -1 (-3575 1900)(-2900 1900);
FORCEPROP 0 LAST CDS_PHYS_NET_NAME OCP_SFF_PRSNT3_R_N
J 0
(-2985 1942);
PAINT MONO (-2985 1942);
DISPLAY INVISIBLE (-2985 1942);
FORCEPROP 2 LAST SIG_NAME OCP_SFF_PRSNT3_R_N
J 0
(-3535 1910);
DISPLAY 0.553191 (-3535 1910);
PAINT WHITE (-3535 1910);
WIRE 16 -1 (-3575 2000)(-2900 2000);
FORCEPROP 0 LAST CDS_PHYS_NET_NAME OCP_SFF_PRSNT2_R_N
J 0
(-2985 2042);
PAINT MONO (-2985 2042);
DISPLAY INVISIBLE (-2985 2042);
FORCEPROP 2 LAST SIG_NAME OCP_SFF_PRSNT2_R_N
J 0
(-3535 2010);
DISPLAY 0.553191 (-3535 2010);
PAINT WHITE (-3535 2010);
WIRE 16 -1 (-3575 2900)(-2900 2900);
FORCEPROP 0 LAST CDS_PHYS_NET_NAME OCP_SFF_PRSNT0_R_N
J 0
(-2985 2942);
PAINT MONO (-2985 2942);
DISPLAY INVISIBLE (-2985 2942);
FORCEPROP 2 LAST SIG_NAME OCP_SFF_PRSNT0_R_N
J 0
(-3535 2910);
DISPLAY 0.553191 (-3535 2910);
PAINT WHITE (-3535 2910);
WIRE 16 -1 (-3550 -100)(-2900 -100);
FORCEPROP 0 LAST CDS_PHYS_NET_NAME OCP_V3_2_PRSNT2_R_N
J 0
(-3010 -58);
PAINT MONO (-3010 -58);
DISPLAY INVISIBLE (-3010 -58);
FORCEPROP 2 LAST SIG_NAME OCP_V3_2_PRSNT2_R_N
J 0
(-3510 -90);
DISPLAY 0.553191 (-3510 -90);
PAINT WHITE (-3510 -90);
WIRE 16 -1 (-3550 -200)(-2900 -200);
FORCEPROP 0 LAST CDS_PHYS_NET_NAME OCP_V3_2_PRSNT3_R_N
J 0
(-3010 -158);
PAINT MONO (-3010 -158);
DISPLAY INVISIBLE (-3010 -158);
FORCEPROP 2 LAST SIG_NAME OCP_V3_2_PRSNT3_R_N
J 0
(-3510 -190);
DISPLAY 0.553191 (-3510 -190);
PAINT WHITE (-3510 -190);
WIRE 16 -1 (-3550 800)(-2900 800);
FORCEPROP 0 LAST CDS_PHYS_NET_NAME OCP_V3_2_PRSNT0_R_N
J 0
(-3010 842);
PAINT MONO (-3010 842);
DISPLAY INVISIBLE (-3010 842);
FORCEPROP 2 LAST SIG_NAME OCP_V3_2_PRSNT0_R_N
J 0
(-3510 810);
DISPLAY 0.553191 (-3510 810);
PAINT WHITE (-3510 810);
WIRE 16 -1 (3300 175)(2500 175);
FORCEPROP 2 LAST SIG_NAME OCP_V3_2_RBT_ARB_OUT
J 0
(2615 185);
DISPLAY 0.680851 (2615 185);
PAINT WHITE (2615 185);
WIRE 16 -1 (3325 -675)(2475 -675);
FORCEPROP 2 LAST SIG_NAME OCP_V3_2_RBT_ARB_IN
J 0
(2590 -665);
DISPLAY 0.680851 (2590 -665);
PAINT WHITE (2590 -665);
WIRE 16 -1 (1900 175)(1275 175);
FORCEPROP 2 LAST SIG_NAME OCP_SFF_RBT_ARB_IN_MUX1
J 0
(1290 185);
DISPLAY 0.553191 (1290 185);
PAINT WHITE (1290 185);
WIRE 16 -1 (900 -575)(1875 -575);
FORCEPROP 2 LAST SIG_NAME OCP_V3_2_PRSNT_ALL_R3_N
J 0
(1115 -565);
DISPLAY 0.510638 (1115 -565);
PAINT WHITE (1115 -565);
FORCEPROP 2 LASTPROP $XRERR UNIQUE?
J 0
(875 -565);
DISPLAY 0.638298 (875 -565);
PAINT MONO (875 -565);
DISPLAY INVISIBLE (875 -565);
WIRE 16 -1 (900 -675)(1875 -675);
FORCEPROP 2 LAST SIG_NAME OCP_SFF_RBT_ARB_IN_MUX2_R
J 0
(1115 -665);
DISPLAY 0.553191 (1115 -665);
PAINT WHITE (1115 -665);
FORCEPROP 2 LASTPROP $XRERR UNIQUE?
J 0
(875 -665);
DISPLAY 0.638298 (875 -665);
PAINT MONO (875 -665);
DISPLAY INVISIBLE (875 -665);
WIRE 16 -1 (-150 -675)(700 -675);
FORCEPROP 2 LAST SIG_NAME OCP_SFF_RBT_ARB_IN_MUX2
J 0
(-135 -665);
DISPLAY 0.553191 (-135 -665);
PAINT WHITE (-135 -665);
WIRE 16 -1 (1725 1450)(725 1450);
FORCEPROP 2 LAST SIG_NAME OCP_SFF_RBT_ARB_IN_MUX1_R
J 0
(1015 1460);
DISPLAY 0.553191 (1015 1460);
PAINT WHITE (1015 1460);
FORCEPROP 2 LASTPROP $XRERR UNIQUE?
J 0
(775 1460);
DISPLAY 0.638298 (775 1460);
PAINT MONO (775 1460);
DISPLAY INVISIBLE (775 1460);
WIRE 16 -1 (2325 2300)(3050 2300);
FORCEPROP 2 LAST SIG_NAME OCP_SFF_RBT_ARB_OUT
J 0
(2440 2310);
DISPLAY 0.553191 (2440 2310);
PAINT WHITE (2440 2310);
WIRE 16 -1 (2325 1450)(3050 1450);
FORCEPROP 2 LAST SIG_NAME OCP_SFF_RBT_ARB_IN
J 0
(2440 1460);
DISPLAY 0.553191 (2440 1460);
PAINT WHITE (2440 1460);
WIRE 16 -1 (2325 2400)(3425 2400);
FORCEPROP 2 LAST SIG_NAME OCP_SFF_NOT_PRSNT_RBT_ARB_IN
J 0
(2440 2410);
DISPLAY 0.638298 (2440 2410);
PAINT WHITE (2440 2410);
FORCEPROP 2 LASTPROP $XRERR UNIQUE?
J 0
(2200 2410);
DISPLAY 0.638298 (2200 2410);
PAINT MONO (2200 2410);
DISPLAY INVISIBLE (2200 2410);
WIRE 16 -1 (3425 2400)(3425 1550);
WIRE 16 -1 (3425 1550)(2325 1550);
WIRE 16 -1 (725 1550)(1725 1550);
FORCEPROP 2 LAST SIG_NAME OCP_SFF_PRSNT_ALL_R3_N
J 0
(1015 1560);
DISPLAY 0.510638 (1015 1560);
PAINT WHITE (1015 1560);
FORCEPROP 2 LASTPROP $XRERR UNIQUE?
J 0
(775 1560);
DISPLAY 0.638298 (775 1560);
PAINT MONO (775 1560);
DISPLAY INVISIBLE (775 1560);
WIRE 16 -1 (525 1450)(-300 1450);
FORCEPROP 2 LAST SIG_NAME OCP_SFF_RBT_ARB_IN_MUX1
J 0
(-260 1460);
DISPLAY 0.553191 (-260 1460);
PAINT WHITE (-260 1460);
WIRE 16 -1 (925 275)(1900 275);
FORCEPROP 2 LAST SIG_NAME OCP_V3_2_PRSNT_ALL_R1_N
J 0
(1290 285);
DISPLAY 0.510638 (1290 285);
PAINT WHITE (1290 285);
FORCEPROP 2 LASTPROP $XRERR UNIQUE?
J 0
(1050 285);
DISPLAY 0.638298 (1050 285);
PAINT MONO (1050 285);
DISPLAY INVISIBLE (1050 285);
WIRE 16 -1 (2500 275)(3650 275);
FORCEPROP 2 LAST SIG_NAME OCP_V3_2_NOT_PRSNT_RBT_ARB_IN
J 0
(2615 285);
DISPLAY 0.638298 (2615 285);
PAINT WHITE (2615 285);
FORCEPROP 2 LASTPROP $XRERR UNIQUE?
J 0
(2375 285);
DISPLAY 0.638298 (2375 285);
PAINT MONO (2375 285);
DISPLAY INVISIBLE (2375 285);
WIRE 16 -1 (3650 275)(3650 -575);
WIRE 16 -1 (3650 -575)(2475 -575);
DOT 1 (-1175 -150);
DOT 1 (-1175 750);
DOT 1 (-1200 2850);
DOT 1 (-1200 1950);
DOT 1 (275 275);
DOT 1 (-2375 1350);
DOT 1 (-2475 3450);
DOT 1 (1325 2975);
DOT 1 (-325 3025);
DOT 1 (1350 2100);
DOT 1 (1525 775);
DOT 1 (1525 -50);
DOT 1 (175 2400);
QUIT
